G04 ================== begin FILE IDENTIFICATION RECORD ==================*
G04 Layout Name:  t6mg_pdb_a_v02_0109_1330.brd*
G04 Film Name:    sst.art*
G04 File Format:  Gerber RS274X*
G04 File Origin:  Cadence Allegro 16.3-S038*
G04 Origin Date:  Mon Jan 13 14:11:51 2014*
G04 *
G04 Layer:  BOARD GEOMETRY/OUTLINE*
G04 Layer:  DRAWING FORMAT/TITLE_BLOCK*
G04 Layer:  MANUFACTURING/TP_TEXT_TOP*
G04 Layer:  REF DES/SILKSCREEN_TOP*
G04 Layer:  PACKAGE GEOMETRY/SILKSCREEN_TOP*
G04 Layer:  MANUFACTURING/PHOTOPLOT_OUTLINE*
G04 Layer:  DRAWING FORMAT/TITLE_DATA_SST*
G04 Layer:  BOARD GEOMETRY/SILKSCREEN_TOP*
G04 *
G04 Offset:    (0.00 0.00)*
G04 Mirror:    No*
G04 Mode:      Positive*
G04 Rotation:  0*
G04 FullContactRelief:  No*
G04 UndefLineWidth:     6.00*
G04 ================== end FILE IDENTIFICATION RECORD ====================*
%FSLAX25Y25*MOIN*%
%IR0*IPPOS*OFA0.00000B0.00000*MIA0B0*SFA1.00000B1.00000*%
%ADD10C,.015*%
%ADD11C,.006*%
%ADD12C,.008*%
%ADD13C,.06212*%
G75*
%LPD*%
G75*
G36*
G01X8954Y337813D02*
Y343107D01*
X14248Y340460D01*
X8954Y337813D01*
G37*
G36*
G01X23970Y1033484D02*
X23014Y1041505D01*
X17746Y1038633D01*
X23970Y1033484D01*
G37*
G36*
G01X25893Y1414328D02*
X28893Y1421828D01*
X22893D01*
X25893Y1414328D01*
G37*
G36*
G01X16119Y1750370D02*
X9820D01*
Y1736197D01*
X16119D01*
Y1750370D01*
G37*
G36*
G01X46423Y84799D02*
X40205Y85684D01*
X43401Y90305D01*
X46423Y84799D01*
G37*
G36*
G01X47207Y1335351D02*
Y1331351D01*
X51207Y1333351D01*
X47207Y1335351D01*
G37*
G36*
G01X45223Y1837737D02*
X40223D01*
X42823Y1831737D01*
X45223Y1837737D01*
G37*
G36*
G01X94634Y163235D02*
X71012D01*
Y360085D01*
X94634D01*
Y163235D01*
G37*
G36*
G01X54979Y220582D02*
X52170Y226200D01*
X57788D01*
X54979Y220582D01*
G37*
G36*
G01X55900Y293516D02*
X54130Y297056D01*
X57670D01*
X55900Y293516D01*
G37*
G36*
G01X71603Y415791D02*
X77221Y418600D01*
Y412982D01*
X71603Y415791D01*
G37*
G36*
G01X55254Y570741D02*
X51945Y577359D01*
X58563D01*
X55254Y570741D01*
G37*
G36*
G01X55715Y1627495D02*
X54392Y1630140D01*
X57038D01*
X55715Y1627495D01*
G37*
G36*
G01X110204Y327252D02*
X99574Y330008D01*
Y324496D01*
X110204Y327252D01*
G37*
G36*
G01X109852Y676616D02*
X99222Y679372D01*
Y673860D01*
X109852Y676616D01*
G37*
G36*
G01X109059Y1024192D02*
X98429Y1026948D01*
Y1021436D01*
X109059Y1024192D01*
G37*
G36*
G01X110383Y1372168D02*
X99753Y1374924D01*
Y1369412D01*
X110383Y1372168D01*
G37*
G36*
G01X109115Y1720232D02*
X98485Y1722988D01*
Y1717476D01*
X109115Y1720232D01*
G37*
G36*
G01X110111Y2067916D02*
X99481Y2070672D01*
Y2065160D01*
X110111Y2067916D01*
G37*
G36*
G01X196652Y56305D02*
G02Y89905I0J16800D01*
G01Y56305D01*
G37*
G36*
G01X197179Y135250D02*
G02Y168850I0J16800D01*
G01Y135250D01*
G37*
G36*
G01X197247Y230768D02*
G02Y264368I0J16800D01*
G01Y230768D01*
G37*
G36*
G01X197707Y314986D02*
G02Y348586I0J16800D01*
G01Y314986D01*
G37*
G36*
G01X196651Y404932D02*
G02Y438532I0J16800D01*
G01Y404932D01*
G37*
G36*
G01X197443Y489717D02*
G02Y523317I0J16800D01*
G01Y489717D01*
G37*
G36*
G01X199778Y581330D02*
G02Y614930I0J16800D01*
G01Y581330D01*
G37*
G36*
G01X197706Y664845D02*
G02Y698445I0J16800D01*
G01Y664845D01*
G37*
G36*
G01X198736Y757726D02*
G02Y791326I0J16800D01*
G01Y757726D01*
G37*
G36*
G01X198496Y839444D02*
G02Y873044I0J16800D01*
G01Y839444D01*
G37*
G36*
G01X203201Y930402D02*
G02Y964002I0J16800D01*
G01Y930402D01*
G37*
G36*
G01X202406Y1015744D02*
G02Y1049344I0J16800D01*
G01Y1015744D01*
G37*
G36*
G01X198140Y1106056D02*
G02Y1139656I0J16800D01*
G01Y1106056D01*
G37*
G36*
G01X198232Y1189433D02*
G02Y1223033I0J16800D01*
G01Y1189433D01*
G37*
G36*
G01X198736Y1282304D02*
G02Y1315904I0J16800D01*
G01Y1282304D01*
G37*
G36*
G01X197442Y1364166D02*
G02Y1397766I0J16800D01*
G01Y1364166D01*
G37*
G36*
G01X196353Y1457362D02*
G02Y1490962I0J16800D01*
G01Y1457362D01*
G37*
G36*
G01X197969Y1540477D02*
G02Y1574077I0J16800D01*
G01Y1540477D01*
G37*
G36*
G01X199033Y1631377D02*
G02Y1664977I0J16800D01*
G01Y1631377D01*
G37*
G36*
G01X198497Y1714551D02*
G02Y1748151I0J16800D01*
G01Y1714551D01*
G37*
G36*
G01X198420Y1806427D02*
G02Y1840027I0J16800D01*
G01Y1806427D01*
G37*
G36*
G01X197179Y1883620D02*
G02Y1917220I0J16800D01*
G01Y1883620D01*
G37*
G36*
G01X199015Y1981930D02*
G02Y2015530I0J16800D01*
G01Y1981930D01*
G37*
G36*
G01X198420Y2026588D02*
G02Y2060188I0J16800D01*
G01Y2026588D01*
G37*
%LPC*%
G75*
G54D13*
X189752Y73105D03*
X190279Y152050D03*
X190347Y247568D03*
X190807Y331786D03*
X189751Y421732D03*
X190543Y506517D03*
X192878Y598130D03*
X190806Y681645D03*
X191836Y774526D03*
X191596Y856244D03*
X196301Y947202D03*
X195506Y1032544D03*
X191240Y1122856D03*
X191332Y1206233D03*
X191836Y1299104D03*
X190542Y1380966D03*
X189453Y1474162D03*
X191069Y1557277D03*
X192133Y1648177D03*
X191597Y1731351D03*
X191520Y1823227D03*
X190279Y1900420D03*
X192115Y1998730D03*
X191520Y2043388D03*
%LPD*%
G75*
G54D10*
G01X18018Y155603D02*
X17268Y156103D01*
X16393Y156436D01*
X15393D01*
X14268Y155936D01*
X13393Y155103D01*
X12768Y154103D01*
X12268Y152436D01*
X12143Y150936D01*
X12393Y149436D01*
X12768Y148436D01*
X13518Y147436D01*
X14393Y146769D01*
X15268Y146436D01*
X16143D01*
X17018Y146769D01*
X17768Y147269D01*
X18393Y147936D01*
G01X23768Y146436D02*
X22768Y146603D01*
X21893Y147269D01*
X21143Y148269D01*
X20643Y149436D01*
X20393Y150769D01*
Y152103D01*
X20643Y153436D01*
X21143Y154603D01*
X21893Y155603D01*
X22768Y156269D01*
X23768Y156436D01*
X24768Y156269D01*
X25643Y155603D01*
X26393Y154603D01*
X26893Y153436D01*
X27143Y152103D01*
Y150769D01*
X26893Y149436D01*
X26393Y148269D01*
X25643Y147269D01*
X24768Y146603D01*
X23768Y146436D01*
G01X29018D02*
Y156436D01*
X32268Y148103D01*
X35518Y156436D01*
Y146436D01*
G01X38393Y154769D02*
X39143Y155769D01*
X40018Y156269D01*
X41018Y156436D01*
X42268Y156103D01*
X43143Y155269D01*
X43393Y154269D01*
X43268Y153269D01*
X42768Y152436D01*
X40268Y150769D01*
X39143Y149603D01*
X38393Y147936D01*
X38143Y146436D01*
X43393D01*
G01X11887Y1902699D02*
X12887Y1901866D01*
X14012Y1901366D01*
X15012D01*
X16012Y1901866D01*
X16762Y1902699D01*
X17137Y1903866D01*
X16887Y1905032D01*
X16262Y1906033D01*
X15137Y1906699D01*
X13637Y1907033D01*
X12762Y1907699D01*
X12387Y1908866D01*
X12637Y1910033D01*
X13262Y1910866D01*
X14137Y1911366D01*
X15012D01*
X15887Y1911033D01*
X16637Y1910199D01*
G01X19262Y1911366D02*
X21012Y1901366D01*
X23012Y1911366D01*
X25012Y1901366D01*
X26762Y1911366D01*
G01X28762Y1903366D02*
X29512Y1902199D01*
X30512Y1901533D01*
X31637Y1901366D01*
X32637Y1901533D01*
X33637Y1902366D01*
X34262Y1903366D01*
X34387Y1904366D01*
X34137Y1905532D01*
X33262Y1906366D01*
X32387Y1906699D01*
X31262D01*
G01X32387D02*
X33137Y1907199D01*
X33762Y1908032D01*
X34012Y1909033D01*
X33762Y1910033D01*
X33137Y1910866D01*
X32012Y1911366D01*
X30887Y1911199D01*
X29762Y1910533D01*
G01X11661Y1984096D02*
X12661Y1983263D01*
X13786Y1982763D01*
X14786D01*
X15786Y1983263D01*
X16536Y1984096D01*
X16911Y1985263D01*
X16661Y1986429D01*
X16036Y1987430D01*
X14911Y1988096D01*
X13411Y1988430D01*
X12536Y1989096D01*
X12161Y1990263D01*
X12411Y1991430D01*
X13036Y1992263D01*
X13911Y1992763D01*
X14786D01*
X15661Y1992430D01*
X16411Y1991596D01*
G01X19036Y1992763D02*
X20786Y1982763D01*
X22786Y1992763D01*
X24786Y1982763D01*
X26536Y1992763D01*
G01X28911Y1991096D02*
X29661Y1992096D01*
X30536Y1992596D01*
X31536Y1992763D01*
X32786Y1992430D01*
X33661Y1991596D01*
X33911Y1990596D01*
X33786Y1989596D01*
X33286Y1988763D01*
X30786Y1987096D01*
X29661Y1985930D01*
X28911Y1984263D01*
X28661Y1982763D01*
X33911D01*
G01X12370Y2056630D02*
X13370Y2055797D01*
X14495Y2055297D01*
X15495D01*
X16495Y2055797D01*
X17245Y2056630D01*
X17620Y2057797D01*
X17370Y2058963D01*
X16745Y2059964D01*
X15620Y2060630D01*
X14120Y2060964D01*
X13245Y2061630D01*
X12870Y2062797D01*
X13120Y2063964D01*
X13745Y2064797D01*
X14620Y2065297D01*
X15495D01*
X16370Y2064964D01*
X17120Y2064130D01*
G01X19745Y2065297D02*
X21495Y2055297D01*
X23495Y2065297D01*
X25495Y2055297D01*
X27245Y2065297D01*
G01X31995Y2055297D02*
Y2065297D01*
X30495Y2063297D01*
G01Y2055297D02*
X33495D01*
G01X42858Y310215D02*
X42108Y310715D01*
X41233Y311048D01*
X40233D01*
X39108Y310548D01*
X38233Y309715D01*
X37608Y308715D01*
X37108Y307048D01*
X36983Y305548D01*
X37233Y304048D01*
X37608Y303048D01*
X38358Y302048D01*
X39233Y301381D01*
X40108Y301048D01*
X40983D01*
X41858Y301381D01*
X42608Y301881D01*
X43233Y302548D01*
G01X48608Y301048D02*
X47608Y301215D01*
X46733Y301881D01*
X45983Y302881D01*
X45483Y304048D01*
X45233Y305381D01*
Y306715D01*
X45483Y308048D01*
X45983Y309215D01*
X46733Y310215D01*
X47608Y310881D01*
X48608Y311048D01*
X49608Y310881D01*
X50483Y310215D01*
X51233Y309215D01*
X51733Y308048D01*
X51983Y306715D01*
Y305381D01*
X51733Y304048D01*
X51233Y302881D01*
X50483Y301881D01*
X49608Y301215D01*
X48608Y301048D01*
G01X53858D02*
Y311048D01*
X57108Y302715D01*
X60358Y311048D01*
Y301048D01*
G01X62858Y302548D02*
X63608Y301715D01*
X64483Y301215D01*
X65608Y301048D01*
X66733Y301381D01*
X67608Y302048D01*
X68233Y303215D01*
X68358Y304548D01*
X68108Y305881D01*
X67483Y306715D01*
X66608Y307381D01*
X65733Y307548D01*
X64858Y307381D01*
X63733Y306715D01*
X64108Y311048D01*
X67483D01*
G01X46910Y315508D02*
X36910D01*
Y318633D01*
X37410Y319633D01*
X38077Y320258D01*
X39410Y320508D01*
X40743Y320258D01*
X41577Y319508D01*
X42077Y318633D01*
Y315508D01*
G01Y318633D02*
X46910Y320508D01*
G01Y323258D02*
X36910D01*
X45243Y326508D01*
X36910Y329758D01*
X46910D01*
G01X50243Y331258D02*
Y338758D01*
G01X46910Y341008D02*
X36910D01*
Y344008D01*
X37410Y345008D01*
X38577Y345758D01*
X39910Y346008D01*
X41243Y345758D01*
X42243Y345133D01*
X42744Y344008D01*
Y341008D01*
G01X36910Y348258D02*
X46910Y350008D01*
X36910Y352008D01*
X46910Y354008D01*
X36910Y355758D01*
G01X46910Y358008D02*
X36910D01*
Y361133D01*
X37410Y362133D01*
X38077Y362758D01*
X39410Y363008D01*
X40743Y362758D01*
X41577Y362008D01*
X42077Y361133D01*
Y358008D01*
G01Y361133D02*
X46910Y363008D01*
G01X73453Y383301D02*
X72953Y382551D01*
X72620Y381676D01*
Y380676D01*
X73120Y379551D01*
X73953Y378676D01*
X74953Y378051D01*
X76620Y377551D01*
X78120Y377426D01*
X79620Y377676D01*
X80620Y378051D01*
X81620Y378801D01*
X82287Y379676D01*
X82620Y380551D01*
Y381426D01*
X82287Y382301D01*
X81787Y383051D01*
X81120Y383676D01*
G01X82620Y389051D02*
X82453Y388051D01*
X81787Y387176D01*
X80787Y386426D01*
X79620Y385926D01*
X78287Y385676D01*
X76953D01*
X75620Y385926D01*
X74453Y386426D01*
X73453Y387176D01*
X72787Y388051D01*
X72620Y389051D01*
X72787Y390051D01*
X73453Y390926D01*
X74453Y391676D01*
X75620Y392176D01*
X76953Y392426D01*
X78287D01*
X79620Y392176D01*
X80787Y391676D01*
X81787Y390926D01*
X82453Y390051D01*
X82620Y389051D01*
G01Y394301D02*
X72620D01*
X80953Y397551D01*
X72620Y400801D01*
X82620D01*
G01X78454Y403676D02*
X77287Y404551D01*
X76620Y405301D01*
X76287Y406301D01*
X76620Y407176D01*
X77287Y407801D01*
X78287Y408301D01*
X79453Y408426D01*
X80453Y408301D01*
X81454Y407801D01*
X82287Y407051D01*
X82620Y406176D01*
X82287Y405176D01*
X81287Y404301D01*
X79787Y403801D01*
X78120Y403676D01*
X75954Y403926D01*
X74787Y404301D01*
X73620Y404926D01*
X72787Y405801D01*
X72620Y406676D01*
X72953Y407551D01*
X73787Y408176D01*
G01X52607Y1012839D02*
X52107Y1012089D01*
X51774Y1011214D01*
Y1010214D01*
X52274Y1009089D01*
X53107Y1008214D01*
X54107Y1007589D01*
X55774Y1007089D01*
X57274Y1006964D01*
X58774Y1007214D01*
X59774Y1007589D01*
X60774Y1008339D01*
X61441Y1009214D01*
X61774Y1010089D01*
Y1010964D01*
X61441Y1011839D01*
X60941Y1012589D01*
X60274Y1013214D01*
G01X61774Y1015339D02*
X51774D01*
X60107Y1018589D01*
X51774Y1021839D01*
X61774D01*
G01X52607Y1038339D02*
X52107Y1037589D01*
X51774Y1036714D01*
Y1035714D01*
X52274Y1034589D01*
X53107Y1033714D01*
X54107Y1033089D01*
X55774Y1032589D01*
X57274Y1032464D01*
X58774Y1032714D01*
X59774Y1033089D01*
X60774Y1033839D01*
X61441Y1034714D01*
X61774Y1035589D01*
Y1036464D01*
X61441Y1037339D01*
X60941Y1038089D01*
X60274Y1038714D01*
G01X61774Y1044089D02*
X61607Y1043089D01*
X60941Y1042214D01*
X59941Y1041464D01*
X58774Y1040964D01*
X57441Y1040714D01*
X56107D01*
X54774Y1040964D01*
X53607Y1041464D01*
X52607Y1042214D01*
X51941Y1043089D01*
X51774Y1044089D01*
X51941Y1045089D01*
X52607Y1045964D01*
X53607Y1046714D01*
X54774Y1047214D01*
X56107Y1047464D01*
X57441D01*
X58774Y1047214D01*
X59941Y1046714D01*
X60941Y1045964D01*
X61607Y1045089D01*
X61774Y1044089D01*
G01Y1049714D02*
X51774D01*
X61774Y1055464D01*
X51774D01*
G01X61774Y1058214D02*
X51774D01*
X61774Y1063964D01*
X51774D01*
G01X61774Y1078089D02*
X51774D01*
X53774Y1076589D01*
G01X61774D02*
Y1079589D01*
G01Y1091964D02*
X51774Y1095089D01*
X61774Y1098214D01*
G01X58274Y1097089D02*
Y1093089D01*
G01X61774Y1100714D02*
X51774D01*
X61774Y1106464D01*
X51774D01*
G01X61774Y1109339D02*
X51774D01*
Y1111839D01*
X52274Y1112839D01*
X52941Y1113589D01*
X53941Y1114214D01*
X55108Y1114714D01*
X56774Y1114839D01*
X58441Y1114714D01*
X59607Y1114214D01*
X60608Y1113589D01*
X61274Y1112839D01*
X61774Y1111839D01*
Y1109339D01*
G01X53441Y1126714D02*
X52441Y1127464D01*
X51941Y1128339D01*
X51774Y1129339D01*
X52107Y1130589D01*
X52941Y1131464D01*
X53941Y1131714D01*
X54941Y1131589D01*
X55774Y1131089D01*
X57441Y1128589D01*
X58607Y1127464D01*
X60274Y1126714D01*
X61774Y1126464D01*
Y1131714D01*
G01X83336Y1810524D02*
X73336D01*
Y1815274D01*
G01X78169Y1813524D02*
Y1810524D01*
G01X83336Y1818274D02*
X73336Y1821399D01*
X83336Y1824524D01*
G01X79836Y1823399D02*
Y1819399D01*
G01X83336Y1827024D02*
X73336D01*
X83336Y1832774D01*
X73336D01*
G01X76249Y49258D02*
X75749Y48508D01*
X75416Y47633D01*
Y46633D01*
X75916Y45508D01*
X76749Y44633D01*
X77749Y44008D01*
X79416Y43508D01*
X80916Y43383D01*
X82416Y43633D01*
X83416Y44008D01*
X84416Y44758D01*
X85083Y45633D01*
X85416Y46508D01*
Y47383D01*
X85083Y48258D01*
X84583Y49008D01*
X83916Y49633D01*
G01X85416Y55008D02*
X85249Y54008D01*
X84583Y53133D01*
X83583Y52383D01*
X82416Y51883D01*
X81083Y51633D01*
X79749D01*
X78416Y51883D01*
X77249Y52383D01*
X76249Y53133D01*
X75583Y54008D01*
X75416Y55008D01*
X75583Y56008D01*
X76249Y56883D01*
X77249Y57633D01*
X78416Y58133D01*
X79749Y58383D01*
X81083D01*
X82416Y58133D01*
X83583Y57633D01*
X84583Y56883D01*
X85249Y56008D01*
X85416Y55008D01*
G01Y60258D02*
X75416D01*
X83749Y63508D01*
X75416Y66758D01*
X85416D01*
G01Y72008D02*
X75416D01*
X77416Y70508D01*
G01X85416D02*
Y73508D01*
G01X97988Y99855D02*
X97488Y99105D01*
X97155Y98230D01*
Y97230D01*
X97655Y96105D01*
X98488Y95230D01*
X99488Y94605D01*
X101155Y94105D01*
X102655Y93980D01*
X104155Y94230D01*
X105155Y94605D01*
X106155Y95355D01*
X106822Y96230D01*
X107155Y97105D01*
Y97980D01*
X106822Y98855D01*
X106322Y99605D01*
X105655Y100230D01*
G01X107155Y102355D02*
X97155D01*
X105488Y105605D01*
X97155Y108855D01*
X107155D01*
G01X110488Y110355D02*
Y117855D01*
G01X107155Y120105D02*
X97155D01*
Y123105D01*
X97655Y124105D01*
X98822Y124855D01*
X100155Y125105D01*
X101488Y124855D01*
X102488Y124230D01*
X102989Y123105D01*
Y120105D01*
G01X97155Y127355D02*
X107155Y129105D01*
X97155Y131105D01*
X107155Y133105D01*
X97155Y134855D01*
G01X107155Y137105D02*
X97155D01*
Y140230D01*
X97655Y141230D01*
X98322Y141855D01*
X99655Y142105D01*
X100988Y141855D01*
X101822Y141105D01*
X102322Y140230D01*
Y137105D01*
G01Y140230D02*
X107155Y142105D01*
G01X110488Y144355D02*
Y151855D01*
G01X97988Y159355D02*
X97488Y158605D01*
X97155Y157730D01*
Y156730D01*
X97655Y155605D01*
X98488Y154730D01*
X99488Y154105D01*
X101155Y153605D01*
X102655Y153480D01*
X104155Y153730D01*
X105155Y154105D01*
X106155Y154855D01*
X106822Y155730D01*
X107155Y156605D01*
Y157480D01*
X106822Y158355D01*
X106322Y159105D01*
X105655Y159730D01*
G01X97155Y165105D02*
X107155D01*
G01X97155Y162230D02*
Y167980D01*
G01Y171105D02*
X107155D01*
Y176105D01*
G01X74495Y527020D02*
X84495D01*
Y532020D01*
G01Y534895D02*
X74495Y538020D01*
X84495Y541145D01*
G01X80995Y540020D02*
Y536020D01*
G01X84495Y543645D02*
X74495D01*
X84495Y549395D01*
X74495D01*
G01X84495Y555020D02*
X74495D01*
X76495Y553520D01*
G01X84495D02*
Y556520D01*
G01X77868Y1582305D02*
X87868D01*
Y1587305D01*
G01Y1590180D02*
X77868Y1593305D01*
X87868Y1596430D01*
G01X84368Y1595305D02*
Y1591305D01*
G01X87868Y1598930D02*
X77868D01*
X87868Y1604680D01*
X77868D01*
G01X79535Y1607930D02*
X78535Y1608680D01*
X78035Y1609555D01*
X77868Y1610555D01*
X78201Y1611805D01*
X79035Y1612680D01*
X80035Y1612930D01*
X81035Y1612805D01*
X81868Y1612305D01*
X83535Y1609805D01*
X84701Y1608680D01*
X86368Y1607930D01*
X87868Y1607680D01*
Y1612930D01*
G01X87251Y1810178D02*
X86751Y1809428D01*
X86418Y1808553D01*
Y1807553D01*
X86918Y1806428D01*
X87751Y1805553D01*
X88751Y1804928D01*
X90418Y1804428D01*
X91918Y1804303D01*
X93418Y1804553D01*
X94418Y1804928D01*
X95418Y1805678D01*
X96085Y1806553D01*
X96418Y1807428D01*
Y1808303D01*
X96085Y1809178D01*
X95585Y1809928D01*
X94918Y1810553D01*
G01X96418Y1815928D02*
X96251Y1814928D01*
X95585Y1814053D01*
X94585Y1813303D01*
X93418Y1812803D01*
X92085Y1812553D01*
X90751D01*
X89418Y1812803D01*
X88251Y1813303D01*
X87251Y1814053D01*
X86585Y1814928D01*
X86418Y1815928D01*
X86585Y1816928D01*
X87251Y1817803D01*
X88251Y1818553D01*
X89418Y1819053D01*
X90751Y1819303D01*
X92085D01*
X93418Y1819053D01*
X94585Y1818553D01*
X95585Y1817803D01*
X96251Y1816928D01*
X96418Y1815928D01*
G01Y1821553D02*
X86418D01*
X96418Y1827303D01*
X86418D01*
G01X96418Y1830053D02*
X86418D01*
X96418Y1835803D01*
X86418D01*
G01X161372Y275332D02*
X151372D01*
Y278332D01*
X151872Y279332D01*
X153039Y280082D01*
X154372Y280332D01*
X155705Y280082D01*
X156705Y279457D01*
X157206Y278332D01*
Y275332D01*
G01X160039Y283707D02*
X160872Y284707D01*
X161372Y285832D01*
Y286832D01*
X160872Y287832D01*
X160039Y288582D01*
X158872Y288957D01*
X157706Y288707D01*
X156705Y288082D01*
X156039Y286957D01*
X155705Y285457D01*
X155039Y284582D01*
X153872Y284207D01*
X152705Y284457D01*
X151872Y285082D01*
X151372Y285957D01*
Y286832D01*
X151705Y287707D01*
X152539Y288457D01*
G01X151372Y292082D02*
X158539D01*
X160039Y292582D01*
X161039Y293582D01*
X161372Y294832D01*
X161039Y296082D01*
X160039Y297082D01*
X158539Y297582D01*
X151372D01*
G01X161372Y303332D02*
X151372D01*
X153372Y301832D01*
G01X161372D02*
Y304832D01*
G01X169530Y657575D02*
X159530D01*
Y660575D01*
X160030Y661575D01*
X161197Y662325D01*
X162530Y662575D01*
X163863Y662325D01*
X164863Y661700D01*
X165364Y660575D01*
Y657575D01*
G01X168197Y665950D02*
X169030Y666950D01*
X169530Y668075D01*
Y669075D01*
X169030Y670075D01*
X168197Y670825D01*
X167030Y671200D01*
X165864Y670950D01*
X164863Y670325D01*
X164197Y669200D01*
X163863Y667700D01*
X163197Y666825D01*
X162030Y666450D01*
X160863Y666700D01*
X160030Y667325D01*
X159530Y668200D01*
Y669075D01*
X159863Y669950D01*
X160697Y670700D01*
G01X159530Y674325D02*
X166697D01*
X168197Y674825D01*
X169197Y675825D01*
X169530Y677075D01*
X169197Y678325D01*
X168197Y679325D01*
X166697Y679825D01*
X159530D01*
G01X161197Y683200D02*
X160197Y683950D01*
X159697Y684825D01*
X159530Y685825D01*
X159863Y687075D01*
X160697Y687950D01*
X161697Y688200D01*
X162697Y688075D01*
X163530Y687575D01*
X165197Y685075D01*
X166363Y683950D01*
X168030Y683200D01*
X169530Y682950D01*
Y688200D01*
G01X160813Y983924D02*
X150813D01*
Y986924D01*
X151313Y987924D01*
X152480Y988674D01*
X153813Y988924D01*
X155146Y988674D01*
X156146Y988049D01*
X156647Y986924D01*
Y983924D01*
G01X159480Y992299D02*
X160313Y993299D01*
X160813Y994424D01*
Y995424D01*
X160313Y996424D01*
X159480Y997174D01*
X158313Y997549D01*
X157147Y997299D01*
X156146Y996674D01*
X155480Y995549D01*
X155146Y994049D01*
X154480Y993174D01*
X153313Y992799D01*
X152146Y993049D01*
X151313Y993674D01*
X150813Y994549D01*
Y995424D01*
X151146Y996299D01*
X151980Y997049D01*
G01X150813Y1000674D02*
X157980D01*
X159480Y1001174D01*
X160480Y1002174D01*
X160813Y1003424D01*
X160480Y1004674D01*
X159480Y1005674D01*
X157980Y1006174D01*
X150813D01*
G01X158813Y1009174D02*
X159980Y1009924D01*
X160646Y1010924D01*
X160813Y1012049D01*
X160646Y1013049D01*
X159813Y1014049D01*
X158813Y1014674D01*
X157813Y1014799D01*
X156647Y1014549D01*
X155813Y1013674D01*
X155480Y1012799D01*
Y1011674D01*
G01Y1012799D02*
X154980Y1013549D01*
X154147Y1014174D01*
X153146Y1014424D01*
X152146Y1014174D01*
X151313Y1013549D01*
X150813Y1012424D01*
X150980Y1011299D01*
X151646Y1010174D01*
G01X170389Y1355971D02*
X160389D01*
Y1358971D01*
X160889Y1359971D01*
X162056Y1360721D01*
X163389Y1360971D01*
X164722Y1360721D01*
X165722Y1360096D01*
X166223Y1358971D01*
Y1355971D01*
G01X169056Y1364346D02*
X169889Y1365346D01*
X170389Y1366471D01*
Y1367471D01*
X169889Y1368471D01*
X169056Y1369221D01*
X167889Y1369596D01*
X166723Y1369346D01*
X165722Y1368721D01*
X165056Y1367596D01*
X164722Y1366096D01*
X164056Y1365221D01*
X162889Y1364846D01*
X161722Y1365096D01*
X160889Y1365721D01*
X160389Y1366596D01*
Y1367471D01*
X160722Y1368346D01*
X161556Y1369096D01*
G01X160389Y1372721D02*
X167556D01*
X169056Y1373221D01*
X170056Y1374221D01*
X170389Y1375471D01*
X170056Y1376721D01*
X169056Y1377721D01*
X167556Y1378221D01*
X160389D01*
G01X170389Y1385471D02*
X160389D01*
X167556Y1380846D01*
Y1387096D01*
G01X173022Y1690056D02*
X163022D01*
Y1693056D01*
X163522Y1694056D01*
X164689Y1694806D01*
X166022Y1695056D01*
X167355Y1694806D01*
X168355Y1694181D01*
X168856Y1693056D01*
Y1690056D01*
G01X171689Y1698431D02*
X172522Y1699431D01*
X173022Y1700556D01*
Y1701556D01*
X172522Y1702556D01*
X171689Y1703306D01*
X170522Y1703681D01*
X169356Y1703431D01*
X168355Y1702806D01*
X167689Y1701681D01*
X167355Y1700181D01*
X166689Y1699306D01*
X165522Y1698931D01*
X164355Y1699181D01*
X163522Y1699806D01*
X163022Y1700681D01*
Y1701556D01*
X163355Y1702431D01*
X164189Y1703181D01*
G01X163022Y1706806D02*
X170189D01*
X171689Y1707306D01*
X172689Y1708306D01*
X173022Y1709556D01*
X172689Y1710806D01*
X171689Y1711806D01*
X170189Y1712306D01*
X163022D01*
G01X171522Y1715306D02*
X172355Y1716056D01*
X172855Y1716931D01*
X173022Y1718056D01*
X172689Y1719181D01*
X172022Y1720056D01*
X170855Y1720681D01*
X169522Y1720806D01*
X168189Y1720556D01*
X167355Y1719931D01*
X166689Y1719056D01*
X166522Y1718181D01*
X166689Y1717306D01*
X167355Y1716181D01*
X163022Y1716556D01*
Y1719931D01*
G01X169692Y2040664D02*
X159692D01*
Y2043664D01*
X160192Y2044664D01*
X161359Y2045414D01*
X162692Y2045664D01*
X164025Y2045414D01*
X165025Y2044789D01*
X165526Y2043664D01*
Y2040664D01*
G01X168359Y2049039D02*
X169192Y2050039D01*
X169692Y2051164D01*
Y2052164D01*
X169192Y2053164D01*
X168359Y2053914D01*
X167192Y2054289D01*
X166026Y2054039D01*
X165025Y2053414D01*
X164359Y2052289D01*
X164025Y2050789D01*
X163359Y2049914D01*
X162192Y2049539D01*
X161025Y2049789D01*
X160192Y2050414D01*
X159692Y2051289D01*
Y2052164D01*
X160025Y2053039D01*
X160859Y2053789D01*
G01X159692Y2057414D02*
X166859D01*
X168359Y2057914D01*
X169359Y2058914D01*
X169692Y2060164D01*
X169359Y2061414D01*
X168359Y2062414D01*
X166859Y2062914D01*
X159692D01*
G01X165526Y2066289D02*
X164359Y2067164D01*
X163692Y2067914D01*
X163359Y2068914D01*
X163692Y2069789D01*
X164359Y2070414D01*
X165359Y2070914D01*
X166525Y2071039D01*
X167525Y2070914D01*
X168526Y2070414D01*
X169359Y2069664D01*
X169692Y2068789D01*
X169359Y2067789D01*
X168359Y2066914D01*
X166859Y2066414D01*
X165192Y2066289D01*
X163026Y2066539D01*
X161859Y2066914D01*
X160692Y2067539D01*
X159859Y2068414D01*
X159692Y2069289D01*
X160025Y2070164D01*
X160859Y2070789D01*
G01X275501Y64581D02*
Y54581D01*
G01X272626Y64581D02*
X278376D01*
G01X281501Y54581D02*
Y64581D01*
X284626D01*
X285626Y64081D01*
X286251Y63414D01*
X286501Y62081D01*
X286251Y60748D01*
X285501Y59914D01*
X284626Y59414D01*
X281501D01*
G01X284626D02*
X286501Y54581D01*
G01X289376D02*
X292501Y64581D01*
X295626Y54581D01*
G01X294501Y58081D02*
X290501D01*
G01X301001Y54581D02*
Y59081D01*
X298501Y64581D01*
G01X303501D02*
X301001Y59081D01*
G01X319001Y59914D02*
X319501Y60414D01*
X319876Y61247D01*
X320126Y62414D01*
X319876Y63414D01*
X319376Y64081D01*
X318501Y64581D01*
X315126D01*
Y54581D01*
X319251D01*
X320126Y55248D01*
X320626Y56248D01*
X320876Y57414D01*
X320626Y58581D01*
X319876Y59581D01*
X319001Y59914D01*
X315126D01*
G01X324001Y54581D02*
Y64581D01*
X327001D01*
X328001Y64081D01*
X328751Y62914D01*
X329001Y61581D01*
X328751Y60248D01*
X328126Y59248D01*
X327001Y58747D01*
X324001D01*
G01X343501Y54581D02*
Y64581D01*
X342001Y62581D01*
G01Y54581D02*
X345001D01*
G01X316522Y1555898D02*
Y1545898D01*
G01X313647Y1555898D02*
X319397D01*
G01X322522Y1545898D02*
Y1555898D01*
X325647D01*
X326647Y1555398D01*
X327272Y1554731D01*
X327522Y1553398D01*
X327272Y1552065D01*
X326522Y1551231D01*
X325647Y1550731D01*
X322522D01*
G01X325647D02*
X327522Y1545898D01*
G01X330397D02*
X333522Y1555898D01*
X336647Y1545898D01*
G01X335522Y1549398D02*
X331522D01*
G01X342022Y1545898D02*
Y1550398D01*
X339522Y1555898D01*
G01X344522D02*
X342022Y1550398D01*
G01X360022Y1551231D02*
X360522Y1551731D01*
X360897Y1552564D01*
X361147Y1553731D01*
X360897Y1554731D01*
X360397Y1555398D01*
X359522Y1555898D01*
X356147D01*
Y1545898D01*
X360272D01*
X361147Y1546565D01*
X361647Y1547565D01*
X361897Y1548731D01*
X361647Y1549898D01*
X360897Y1550898D01*
X360022Y1551231D01*
X356147D01*
G01X365022Y1545898D02*
Y1555898D01*
X368022D01*
X369022Y1555398D01*
X369772Y1554231D01*
X370022Y1552898D01*
X369772Y1551565D01*
X369147Y1550565D01*
X368022Y1550064D01*
X365022D01*
G01X384522Y1545898D02*
Y1555898D01*
X383022Y1553898D01*
G01Y1545898D02*
X386022D01*
G01X393022Y1555898D02*
X392022Y1555565D01*
X391272Y1554731D01*
X390772Y1553731D01*
X390397Y1552398D01*
X390272Y1550898D01*
X390397Y1549398D01*
X390772Y1548065D01*
X391272Y1547064D01*
X392022Y1546231D01*
X393022Y1545898D01*
X394022Y1546231D01*
X394772Y1547064D01*
X395272Y1548065D01*
X395647Y1549398D01*
X395772Y1550898D01*
X395647Y1552398D01*
X395272Y1553731D01*
X394772Y1554731D01*
X394022Y1555565D01*
X393022Y1555898D01*
G01X314592Y1739257D02*
Y1729257D01*
G01X311717Y1739257D02*
X317467D01*
G01X320592Y1729257D02*
Y1739257D01*
X323717D01*
X324717Y1738757D01*
X325342Y1738090D01*
X325592Y1736757D01*
X325342Y1735424D01*
X324592Y1734590D01*
X323717Y1734090D01*
X320592D01*
G01X323717D02*
X325592Y1729257D01*
G01X328467D02*
X331592Y1739257D01*
X334717Y1729257D01*
G01X333592Y1732757D02*
X329592D01*
G01X340092Y1729257D02*
Y1733757D01*
X337592Y1739257D01*
G01X342592D02*
X340092Y1733757D01*
G01X358092Y1734590D02*
X358592Y1735090D01*
X358967Y1735923D01*
X359217Y1737090D01*
X358967Y1738090D01*
X358467Y1738757D01*
X357592Y1739257D01*
X354217D01*
Y1729257D01*
X358342D01*
X359217Y1729924D01*
X359717Y1730924D01*
X359967Y1732090D01*
X359717Y1733257D01*
X358967Y1734257D01*
X358092Y1734590D01*
X354217D01*
G01X363092Y1729257D02*
Y1739257D01*
X366092D01*
X367092Y1738757D01*
X367842Y1737590D01*
X368092Y1736257D01*
X367842Y1734924D01*
X367217Y1733924D01*
X366092Y1733423D01*
X363092D01*
G01X382592Y1729257D02*
Y1739257D01*
X381092Y1737257D01*
G01Y1729257D02*
X384092D01*
G01X391092D02*
Y1739257D01*
X389592Y1737257D01*
G01Y1729257D02*
X392592D01*
G01X320912Y166746D02*
Y156746D01*
G01X318037Y166746D02*
X323787D01*
G01X326912Y156746D02*
Y166746D01*
X330037D01*
X331037Y166246D01*
X331662Y165579D01*
X331912Y164246D01*
X331662Y162913D01*
X330912Y162079D01*
X330037Y161579D01*
X326912D01*
G01X330037D02*
X331912Y156746D01*
G01X334787D02*
X337912Y166746D01*
X341037Y156746D01*
G01X339912Y160246D02*
X335912D01*
G01X346412Y156746D02*
Y161246D01*
X343912Y166746D01*
G01X348912D02*
X346412Y161246D01*
G01X364412Y162079D02*
X364912Y162579D01*
X365287Y163412D01*
X365537Y164579D01*
X365287Y165579D01*
X364787Y166246D01*
X363912Y166746D01*
X360537D01*
Y156746D01*
X364662D01*
X365537Y157413D01*
X366037Y158413D01*
X366287Y159579D01*
X366037Y160746D01*
X365287Y161746D01*
X364412Y162079D01*
X360537D01*
G01X369412Y156746D02*
Y166746D01*
X372412D01*
X373412Y166246D01*
X374162Y165079D01*
X374412Y163746D01*
X374162Y162413D01*
X373537Y161413D01*
X372412Y160912D01*
X369412D01*
G01X386537Y165079D02*
X387287Y166079D01*
X388162Y166579D01*
X389162Y166746D01*
X390412Y166413D01*
X391287Y165579D01*
X391537Y164579D01*
X391412Y163579D01*
X390912Y162746D01*
X388412Y161079D01*
X387287Y159913D01*
X386537Y158246D01*
X386287Y156746D01*
X391537D01*
G01X329112Y339167D02*
Y329167D01*
G01X326237Y339167D02*
X331987D01*
G01X335112Y329167D02*
Y339167D01*
X338237D01*
X339237Y338667D01*
X339862Y338000D01*
X340112Y336667D01*
X339862Y335334D01*
X339112Y334500D01*
X338237Y334000D01*
X335112D01*
G01X338237D02*
X340112Y329167D01*
G01X342987D02*
X346112Y339167D01*
X349237Y329167D01*
G01X348112Y332667D02*
X344112D01*
G01X354612Y329167D02*
Y333667D01*
X352112Y339167D01*
G01X357112D02*
X354612Y333667D01*
G01X372612Y334500D02*
X373112Y335000D01*
X373487Y335833D01*
X373737Y337000D01*
X373487Y338000D01*
X372987Y338667D01*
X372112Y339167D01*
X368737D01*
Y329167D01*
X372862D01*
X373737Y329834D01*
X374237Y330834D01*
X374487Y332000D01*
X374237Y333167D01*
X373487Y334167D01*
X372612Y334500D01*
X368737D01*
G01X377612Y329167D02*
Y339167D01*
X380612D01*
X381612Y338667D01*
X382362Y337500D01*
X382612Y336167D01*
X382362Y334834D01*
X381737Y333834D01*
X380612Y333333D01*
X377612D01*
G01X394362Y331167D02*
X395112Y330000D01*
X396112Y329334D01*
X397237Y329167D01*
X398237Y329334D01*
X399237Y330167D01*
X399862Y331167D01*
X399987Y332167D01*
X399737Y333333D01*
X398862Y334167D01*
X397987Y334500D01*
X396862D01*
G01X397987D02*
X398737Y335000D01*
X399362Y335833D01*
X399612Y336834D01*
X399362Y337834D01*
X398737Y338667D01*
X397612Y339167D01*
X396487Y339000D01*
X395362Y338334D01*
G01X327717Y514034D02*
Y504034D01*
G01X324842Y514034D02*
X330592D01*
G01X333717Y504034D02*
Y514034D01*
X336842D01*
X337842Y513534D01*
X338467Y512867D01*
X338717Y511534D01*
X338467Y510201D01*
X337717Y509367D01*
X336842Y508867D01*
X333717D01*
G01X336842D02*
X338717Y504034D01*
G01X341592D02*
X344717Y514034D01*
X347842Y504034D01*
G01X346717Y507534D02*
X342717D01*
G01X353217Y504034D02*
Y508534D01*
X350717Y514034D01*
G01X355717D02*
X353217Y508534D01*
G01X371217Y509367D02*
X371717Y509867D01*
X372092Y510700D01*
X372342Y511867D01*
X372092Y512867D01*
X371592Y513534D01*
X370717Y514034D01*
X367342D01*
Y504034D01*
X371467D01*
X372342Y504701D01*
X372842Y505701D01*
X373092Y506867D01*
X372842Y508034D01*
X372092Y509034D01*
X371217Y509367D01*
X367342D01*
G01X376217Y504034D02*
Y514034D01*
X379217D01*
X380217Y513534D01*
X380967Y512367D01*
X381217Y511034D01*
X380967Y509701D01*
X380342Y508701D01*
X379217Y508200D01*
X376217D01*
G01X397217Y504034D02*
Y514034D01*
X392592Y506867D01*
X398842D01*
G01X325787Y688129D02*
Y678129D01*
G01X322912Y688129D02*
X328662D01*
G01X331787Y678129D02*
Y688129D01*
X334912D01*
X335912Y687629D01*
X336537Y686962D01*
X336787Y685629D01*
X336537Y684296D01*
X335787Y683462D01*
X334912Y682962D01*
X331787D01*
G01X334912D02*
X336787Y678129D01*
G01X339662D02*
X342787Y688129D01*
X345912Y678129D01*
G01X344787Y681629D02*
X340787D01*
G01X351287Y678129D02*
Y682629D01*
X348787Y688129D01*
G01X353787D02*
X351287Y682629D01*
G01X369287Y683462D02*
X369787Y683962D01*
X370162Y684795D01*
X370412Y685962D01*
X370162Y686962D01*
X369662Y687629D01*
X368787Y688129D01*
X365412D01*
Y678129D01*
X369537D01*
X370412Y678796D01*
X370912Y679796D01*
X371162Y680962D01*
X370912Y682129D01*
X370162Y683129D01*
X369287Y683462D01*
X365412D01*
G01X374287Y678129D02*
Y688129D01*
X377287D01*
X378287Y687629D01*
X379037Y686462D01*
X379287Y685129D01*
X379037Y683796D01*
X378412Y682796D01*
X377287Y682295D01*
X374287D01*
G01X391037Y679629D02*
X391787Y678796D01*
X392662Y678296D01*
X393787Y678129D01*
X394912Y678462D01*
X395787Y679129D01*
X396412Y680296D01*
X396537Y681629D01*
X396287Y682962D01*
X395662Y683796D01*
X394787Y684462D01*
X393912Y684629D01*
X393037Y684462D01*
X391912Y683796D01*
X392287Y688129D01*
X395662D01*
G01X328103Y864925D02*
Y854925D01*
G01X325228Y864925D02*
X330978D01*
G01X334103Y854925D02*
Y864925D01*
X337228D01*
X338228Y864425D01*
X338853Y863758D01*
X339103Y862425D01*
X338853Y861092D01*
X338103Y860258D01*
X337228Y859758D01*
X334103D01*
G01X337228D02*
X339103Y854925D01*
G01X341978D02*
X345103Y864925D01*
X348228Y854925D01*
G01X347103Y858425D02*
X343103D01*
G01X353603Y854925D02*
Y859425D01*
X351103Y864925D01*
G01X356103D02*
X353603Y859425D01*
G01X371603Y860258D02*
X372103Y860758D01*
X372478Y861591D01*
X372728Y862758D01*
X372478Y863758D01*
X371978Y864425D01*
X371103Y864925D01*
X367728D01*
Y854925D01*
X371853D01*
X372728Y855592D01*
X373228Y856592D01*
X373478Y857758D01*
X373228Y858925D01*
X372478Y859925D01*
X371603Y860258D01*
X367728D01*
G01X376603Y854925D02*
Y864925D01*
X379603D01*
X380603Y864425D01*
X381353Y863258D01*
X381603Y861925D01*
X381353Y860592D01*
X380728Y859592D01*
X379603Y859091D01*
X376603D01*
G01X393728D02*
X394603Y860258D01*
X395353Y860925D01*
X396353Y861258D01*
X397228Y860925D01*
X397853Y860258D01*
X398353Y859258D01*
X398478Y858092D01*
X398353Y857092D01*
X397853Y856091D01*
X397103Y855258D01*
X396228Y854925D01*
X395228Y855258D01*
X394353Y856258D01*
X393853Y857758D01*
X393728Y859425D01*
X393978Y861591D01*
X394353Y862758D01*
X394978Y863925D01*
X395853Y864758D01*
X396728Y864925D01*
X397603Y864592D01*
X398228Y863758D01*
G01X327331Y1040949D02*
Y1030949D01*
G01X324456Y1040949D02*
X330206D01*
G01X333331Y1030949D02*
Y1040949D01*
X336456D01*
X337456Y1040449D01*
X338081Y1039782D01*
X338331Y1038449D01*
X338081Y1037116D01*
X337331Y1036282D01*
X336456Y1035782D01*
X333331D01*
G01X336456D02*
X338331Y1030949D01*
G01X341206D02*
X344331Y1040949D01*
X347456Y1030949D01*
G01X346331Y1034449D02*
X342331D01*
G01X352831Y1030949D02*
Y1035449D01*
X350331Y1040949D01*
G01X355331D02*
X352831Y1035449D01*
G01X370831Y1036282D02*
X371331Y1036782D01*
X371706Y1037615D01*
X371956Y1038782D01*
X371706Y1039782D01*
X371206Y1040449D01*
X370331Y1040949D01*
X366956D01*
Y1030949D01*
X371081D01*
X371956Y1031616D01*
X372456Y1032616D01*
X372706Y1033782D01*
X372456Y1034949D01*
X371706Y1035949D01*
X370831Y1036282D01*
X366956D01*
G01X375831Y1030949D02*
Y1040949D01*
X378831D01*
X379831Y1040449D01*
X380581Y1039282D01*
X380831Y1037949D01*
X380581Y1036616D01*
X379956Y1035616D01*
X378831Y1035115D01*
X375831D01*
G01X395081Y1030949D02*
X395331Y1033116D01*
X395706Y1034949D01*
X396206Y1036616D01*
X396831Y1038449D01*
X397831Y1040949D01*
X392831D01*
G01X328103Y1216973D02*
Y1206973D01*
G01X325228Y1216973D02*
X330978D01*
G01X334103Y1206973D02*
Y1216973D01*
X337228D01*
X338228Y1216473D01*
X338853Y1215806D01*
X339103Y1214473D01*
X338853Y1213140D01*
X338103Y1212306D01*
X337228Y1211806D01*
X334103D01*
G01X337228D02*
X339103Y1206973D01*
G01X341978D02*
X345103Y1216973D01*
X348228Y1206973D01*
G01X347103Y1210473D02*
X343103D01*
G01X353603Y1206973D02*
Y1211473D01*
X351103Y1216973D01*
G01X356103D02*
X353603Y1211473D01*
G01X371603Y1212306D02*
X372103Y1212806D01*
X372478Y1213639D01*
X372728Y1214806D01*
X372478Y1215806D01*
X371978Y1216473D01*
X371103Y1216973D01*
X367728D01*
Y1206973D01*
X371853D01*
X372728Y1207640D01*
X373228Y1208640D01*
X373478Y1209806D01*
X373228Y1210973D01*
X372478Y1211973D01*
X371603Y1212306D01*
X367728D01*
G01X376603Y1206973D02*
Y1216973D01*
X379603D01*
X380603Y1216473D01*
X381353Y1215306D01*
X381603Y1213973D01*
X381353Y1212640D01*
X380728Y1211640D01*
X379603Y1211139D01*
X376603D01*
G01X396103Y1206973D02*
X396978Y1207140D01*
X397978Y1207640D01*
X398603Y1208473D01*
X398853Y1209640D01*
X398603Y1210806D01*
X397853Y1211806D01*
X396728Y1212306D01*
X395478D01*
X394728Y1212640D01*
X394103Y1213473D01*
X393853Y1214640D01*
X394228Y1215806D01*
X395103Y1216640D01*
X396103Y1216973D01*
X397103Y1216640D01*
X397978Y1215806D01*
X398353Y1214640D01*
X398103Y1213473D01*
X397478Y1212640D01*
X396728Y1212306D01*
X395478D01*
X394353Y1211806D01*
X393603Y1210806D01*
X393353Y1209640D01*
X393603Y1208473D01*
X394228Y1207640D01*
X395228Y1207140D01*
X396103Y1206973D01*
G01X325015Y1389524D02*
Y1379524D01*
G01X322140Y1389524D02*
X327890D01*
G01X331015Y1379524D02*
Y1389524D01*
X334140D01*
X335140Y1389024D01*
X335765Y1388357D01*
X336015Y1387024D01*
X335765Y1385691D01*
X335015Y1384857D01*
X334140Y1384357D01*
X331015D01*
G01X334140D02*
X336015Y1379524D01*
G01X338890D02*
X342015Y1389524D01*
X345140Y1379524D01*
G01X344015Y1383024D02*
X340015D01*
G01X350515Y1379524D02*
Y1384024D01*
X348015Y1389524D01*
G01X353015D02*
X350515Y1384024D01*
G01X368515Y1384857D02*
X369015Y1385357D01*
X369390Y1386190D01*
X369640Y1387357D01*
X369390Y1388357D01*
X368890Y1389024D01*
X368015Y1389524D01*
X364640D01*
Y1379524D01*
X368765D01*
X369640Y1380191D01*
X370140Y1381191D01*
X370390Y1382357D01*
X370140Y1383524D01*
X369390Y1384524D01*
X368515Y1384857D01*
X364640D01*
G01X373515Y1379524D02*
Y1389524D01*
X376515D01*
X377515Y1389024D01*
X378265Y1387857D01*
X378515Y1386524D01*
X378265Y1385191D01*
X377640Y1384191D01*
X376515Y1383690D01*
X373515D01*
G01X390890Y1380690D02*
X391765Y1379857D01*
X392765Y1379524D01*
X393765Y1379857D01*
X394640Y1380857D01*
X395265Y1382357D01*
X395515Y1383857D01*
Y1385691D01*
X395265Y1387191D01*
X394640Y1388524D01*
X393890Y1389191D01*
X393015Y1389524D01*
X392015Y1389191D01*
X391265Y1388524D01*
X390765Y1387524D01*
X390515Y1386190D01*
X390765Y1385024D01*
X391390Y1383857D01*
X392140Y1383190D01*
X393015Y1383024D01*
X394015Y1383357D01*
X394765Y1384191D01*
X395515Y1385691D01*
G01X320768Y1909877D02*
Y1899877D01*
G01X317893Y1909877D02*
X323643D01*
G01X326768Y1899877D02*
Y1909877D01*
X329893D01*
X330893Y1909377D01*
X331518Y1908710D01*
X331768Y1907377D01*
X331518Y1906044D01*
X330768Y1905210D01*
X329893Y1904710D01*
X326768D01*
G01X329893D02*
X331768Y1899877D01*
G01X334643D02*
X337768Y1909877D01*
X340893Y1899877D01*
G01X339768Y1903377D02*
X335768D01*
G01X346268Y1899877D02*
Y1904377D01*
X343768Y1909877D01*
G01X348768D02*
X346268Y1904377D01*
G01X364268Y1905210D02*
X364768Y1905710D01*
X365143Y1906543D01*
X365393Y1907710D01*
X365143Y1908710D01*
X364643Y1909377D01*
X363768Y1909877D01*
X360393D01*
Y1899877D01*
X364518D01*
X365393Y1900544D01*
X365893Y1901544D01*
X366143Y1902710D01*
X365893Y1903877D01*
X365143Y1904877D01*
X364268Y1905210D01*
X360393D01*
G01X369268Y1899877D02*
Y1909877D01*
X372268D01*
X373268Y1909377D01*
X374018Y1908210D01*
X374268Y1906877D01*
X374018Y1905544D01*
X373393Y1904544D01*
X372268Y1904043D01*
X369268D01*
G01X388768Y1899877D02*
Y1909877D01*
X387268Y1907877D01*
G01Y1899877D02*
X390268D01*
G01X394893Y1908210D02*
X395643Y1909210D01*
X396518Y1909710D01*
X397518Y1909877D01*
X398768Y1909544D01*
X399643Y1908710D01*
X399893Y1907710D01*
X399768Y1906710D01*
X399268Y1905877D01*
X396768Y1904210D01*
X395643Y1903044D01*
X394893Y1901377D01*
X394643Y1899877D01*
X399893D01*
G54D11*
G01X-723776Y2987387D02*
Y-376795D01*
Y-489221D01*
X1782976D01*
Y-376795D01*
Y2987387D01*
X-723776D01*
G01X-4000Y-62500D02*
Y-137500D01*
X496000D01*
Y-62500D01*
X-4000D01*
G01X397638Y0D02*
G03X405512Y7874I0J7874D01*
G01Y2078740D01*
G03X397638Y2086614I-7874J0D01*
G01X104331D01*
G03X98425Y2080709I-1J-5905D01*
G01Y2076772D01*
G02X92520Y2070866I-5906J0D01*
G01X5906D01*
G03X0Y2064961I-1J-5905D01*
G01Y21654D01*
G03X5906Y15748I5906J0D01*
G01X92520D01*
G02X98425Y9843I0J-5905D01*
G01Y5906D01*
G03X104331Y0I5906J0D01*
G01X397638D01*
G01X8000Y-127500D02*
Y-132500D01*
G01X6543Y-127500D02*
X9457D01*
G01X14367Y-132500D02*
X11833D01*
Y-127500D01*
X14367D01*
G01X13353Y-129917D02*
X11833D01*
G01X16933Y-127500D02*
Y-132500D01*
X19467D01*
G01X23300Y-132667D02*
X23173Y-132583D01*
Y-132417D01*
X23300Y-132333D01*
X23427Y-132417D01*
Y-132583D01*
X23300Y-132667D01*
G01Y-130417D02*
X23173Y-130333D01*
Y-130167D01*
X23300Y-130083D01*
X23427Y-130167D01*
Y-130333D01*
X23300Y-130417D01*
G01X28083Y-134167D02*
X27450Y-133333D01*
X27133Y-132500D01*
Y-129167D01*
X27450Y-128333D01*
X28083Y-127500D01*
G01X33500D02*
X32993Y-127667D01*
X32613Y-128083D01*
X32360Y-128583D01*
X32170Y-129250D01*
X32107Y-130000D01*
X32170Y-130750D01*
X32360Y-131417D01*
X32613Y-131917D01*
X32993Y-132333D01*
X33500Y-132500D01*
X34007Y-132333D01*
X34387Y-131917D01*
X34640Y-131417D01*
X34830Y-130750D01*
X34893Y-130000D01*
X34830Y-129250D01*
X34640Y-128583D01*
X34387Y-128083D01*
X34007Y-127667D01*
X33500Y-127500D01*
G01X37207Y-131500D02*
X37587Y-132083D01*
X38093Y-132417D01*
X38663Y-132500D01*
X39170Y-132417D01*
X39677Y-132000D01*
X39993Y-131500D01*
X40057Y-131000D01*
X39930Y-130417D01*
X39487Y-130000D01*
X39043Y-129833D01*
X38473D01*
G01X39043D02*
X39423Y-129583D01*
X39740Y-129167D01*
X39867Y-128667D01*
X39740Y-128167D01*
X39423Y-127750D01*
X38853Y-127500D01*
X38283Y-127583D01*
X37713Y-127917D01*
G01X44017Y-134167D02*
X44650Y-133333D01*
X44967Y-132500D01*
Y-129167D01*
X44650Y-128333D01*
X44017Y-127500D01*
G01X47407Y-131500D02*
X47787Y-132083D01*
X48293Y-132417D01*
X48863Y-132500D01*
X49370Y-132417D01*
X49877Y-132000D01*
X50193Y-131500D01*
X50257Y-131000D01*
X50130Y-130417D01*
X49687Y-130000D01*
X49243Y-129833D01*
X48673D01*
G01X49243D02*
X49623Y-129583D01*
X49940Y-129167D01*
X50067Y-128667D01*
X49940Y-128167D01*
X49623Y-127750D01*
X49053Y-127500D01*
X48483Y-127583D01*
X47913Y-127917D01*
G01X52697Y-128333D02*
X53077Y-127833D01*
X53520Y-127583D01*
X54027Y-127500D01*
X54660Y-127667D01*
X55103Y-128083D01*
X55230Y-128583D01*
X55167Y-129083D01*
X54913Y-129500D01*
X53647Y-130333D01*
X53077Y-130917D01*
X52697Y-131750D01*
X52570Y-132500D01*
X55230D01*
G01X58873D02*
X59000Y-131417D01*
X59190Y-130500D01*
X59443Y-129667D01*
X59760Y-128750D01*
X60267Y-127500D01*
X57733D01*
G01X63277Y-130833D02*
X64923D01*
G01X67997Y-128333D02*
X68377Y-127833D01*
X68820Y-127583D01*
X69327Y-127500D01*
X69960Y-127667D01*
X70403Y-128083D01*
X70530Y-128583D01*
X70467Y-129083D01*
X70213Y-129500D01*
X68947Y-130333D01*
X68377Y-130917D01*
X67997Y-131750D01*
X67870Y-132500D01*
X70530D01*
G01X72907Y-131500D02*
X73287Y-132083D01*
X73793Y-132417D01*
X74363Y-132500D01*
X74870Y-132417D01*
X75377Y-132000D01*
X75693Y-131500D01*
X75757Y-131000D01*
X75630Y-130417D01*
X75187Y-130000D01*
X74743Y-129833D01*
X74173D01*
G01X74743D02*
X75123Y-129583D01*
X75440Y-129167D01*
X75567Y-128667D01*
X75440Y-128167D01*
X75123Y-127750D01*
X74553Y-127500D01*
X73983Y-127583D01*
X73413Y-127917D01*
G01X80160Y-132500D02*
Y-127500D01*
X77817Y-131083D01*
X80983D01*
G01X83107Y-131750D02*
X83487Y-132167D01*
X83930Y-132417D01*
X84500Y-132500D01*
X85070Y-132333D01*
X85513Y-132000D01*
X85830Y-131417D01*
X85893Y-130750D01*
X85767Y-130083D01*
X85450Y-129667D01*
X85007Y-129333D01*
X84563Y-129250D01*
X84120Y-129333D01*
X83550Y-129667D01*
X83740Y-127500D01*
X85450D01*
G01X93497Y-132500D02*
Y-127500D01*
X95903D01*
G01X95017Y-129917D02*
X93497D01*
G01X98217Y-132500D02*
X99800Y-127500D01*
X101383Y-132500D01*
G01X100813Y-130750D02*
X98787D01*
G01X103570Y-132500D02*
X106230Y-127500D01*
G01X103570D02*
X106230Y-132500D01*
G01X110000Y-132667D02*
X109873Y-132583D01*
Y-132417D01*
X110000Y-132333D01*
X110127Y-132417D01*
Y-132583D01*
X110000Y-132667D01*
G01Y-130417D02*
X109873Y-130333D01*
Y-130167D01*
X110000Y-130083D01*
X110127Y-130167D01*
Y-130333D01*
X110000Y-130417D01*
G01X114783Y-134167D02*
X114150Y-133333D01*
X113833Y-132500D01*
Y-129167D01*
X114150Y-128333D01*
X114783Y-127500D01*
G01X120200D02*
X119693Y-127667D01*
X119313Y-128083D01*
X119060Y-128583D01*
X118870Y-129250D01*
X118807Y-130000D01*
X118870Y-130750D01*
X119060Y-131417D01*
X119313Y-131917D01*
X119693Y-132333D01*
X120200Y-132500D01*
X120707Y-132333D01*
X121087Y-131917D01*
X121340Y-131417D01*
X121530Y-130750D01*
X121593Y-130000D01*
X121530Y-129250D01*
X121340Y-128583D01*
X121087Y-128083D01*
X120707Y-127667D01*
X120200Y-127500D01*
G01X123907Y-131500D02*
X124287Y-132083D01*
X124793Y-132417D01*
X125363Y-132500D01*
X125870Y-132417D01*
X126377Y-132000D01*
X126693Y-131500D01*
X126757Y-131000D01*
X126630Y-130417D01*
X126187Y-130000D01*
X125743Y-129833D01*
X125173D01*
G01X125743D02*
X126123Y-129583D01*
X126440Y-129167D01*
X126567Y-128667D01*
X126440Y-128167D01*
X126123Y-127750D01*
X125553Y-127500D01*
X124983Y-127583D01*
X124413Y-127917D01*
G01X130717Y-134167D02*
X131350Y-133333D01*
X131667Y-132500D01*
Y-129167D01*
X131350Y-128333D01*
X130717Y-127500D01*
G01X134107Y-131500D02*
X134487Y-132083D01*
X134993Y-132417D01*
X135563Y-132500D01*
X136070Y-132417D01*
X136577Y-132000D01*
X136893Y-131500D01*
X136957Y-131000D01*
X136830Y-130417D01*
X136387Y-130000D01*
X135943Y-129833D01*
X135373D01*
G01X135943D02*
X136323Y-129583D01*
X136640Y-129167D01*
X136767Y-128667D01*
X136640Y-128167D01*
X136323Y-127750D01*
X135753Y-127500D01*
X135183Y-127583D01*
X134613Y-127917D01*
G01X139523Y-131917D02*
X139967Y-132333D01*
X140473Y-132500D01*
X140980Y-132333D01*
X141423Y-131833D01*
X141740Y-131083D01*
X141867Y-130333D01*
Y-129417D01*
X141740Y-128667D01*
X141423Y-128000D01*
X141043Y-127667D01*
X140600Y-127500D01*
X140093Y-127667D01*
X139713Y-128000D01*
X139460Y-128500D01*
X139333Y-129167D01*
X139460Y-129750D01*
X139777Y-130333D01*
X140157Y-130667D01*
X140600Y-130750D01*
X141107Y-130583D01*
X141487Y-130167D01*
X141867Y-129417D01*
G01X145573Y-132500D02*
X145700Y-131417D01*
X145890Y-130500D01*
X146143Y-129667D01*
X146460Y-128750D01*
X146967Y-127500D01*
X144433D01*
G01X149977Y-130833D02*
X151623D01*
G01X154507Y-131500D02*
X154887Y-132083D01*
X155393Y-132417D01*
X155963Y-132500D01*
X156470Y-132417D01*
X156977Y-132000D01*
X157293Y-131500D01*
X157357Y-131000D01*
X157230Y-130417D01*
X156787Y-130000D01*
X156343Y-129833D01*
X155773D01*
G01X156343D02*
X156723Y-129583D01*
X157040Y-129167D01*
X157167Y-128667D01*
X157040Y-128167D01*
X156723Y-127750D01*
X156153Y-127500D01*
X155583Y-127583D01*
X155013Y-127917D01*
G01X159797Y-130417D02*
X160240Y-129833D01*
X160620Y-129500D01*
X161127Y-129333D01*
X161570Y-129500D01*
X161887Y-129833D01*
X162140Y-130333D01*
X162203Y-130917D01*
X162140Y-131417D01*
X161887Y-131917D01*
X161507Y-132333D01*
X161063Y-132500D01*
X160557Y-132333D01*
X160113Y-131833D01*
X159860Y-131083D01*
X159797Y-130250D01*
X159923Y-129167D01*
X160113Y-128583D01*
X160430Y-128000D01*
X160873Y-127583D01*
X161317Y-127500D01*
X161760Y-127667D01*
X162077Y-128083D01*
G01X166100Y-132500D02*
Y-127500D01*
X165340Y-128500D01*
G01Y-132500D02*
X166860D01*
G01X171960D02*
Y-127500D01*
X169617Y-131083D01*
X172783D01*
G01X191000Y-62500D02*
Y-137500D01*
G01Y-112500D02*
X294000D01*
Y-87500D01*
G01X191000D02*
X294000D01*
G01X301507Y-122500D02*
Y-117500D01*
X302773D01*
X303280Y-117750D01*
X303660Y-118083D01*
X303977Y-118583D01*
X304230Y-119167D01*
X304293Y-120000D01*
X304230Y-120833D01*
X303977Y-121417D01*
X303660Y-121917D01*
X303280Y-122250D01*
X302773Y-122500D01*
X301507D01*
G01X306417D02*
X308000Y-117500D01*
X309583Y-122500D01*
G01X309013Y-120750D02*
X306987D01*
G01X313100Y-117500D02*
Y-122500D01*
G01X311643Y-117500D02*
X314557D01*
G01X319467Y-122500D02*
X316933D01*
Y-117500D01*
X319467D01*
G01X318453Y-119917D02*
X316933D01*
G01X323300Y-122667D02*
X323173Y-122583D01*
Y-122417D01*
X323300Y-122333D01*
X323427Y-122417D01*
Y-122583D01*
X323300Y-122667D01*
G01Y-120417D02*
X323173Y-120333D01*
Y-120167D01*
X323300Y-120083D01*
X323427Y-120167D01*
Y-120333D01*
X323300Y-120417D01*
G01X296000Y-62500D02*
Y-137500D01*
G01X294000Y-62500D02*
Y-137500D01*
G01X301633Y-97500D02*
Y-92500D01*
X303153D01*
X303660Y-92750D01*
X304040Y-93333D01*
X304167Y-94000D01*
X304040Y-94667D01*
X303723Y-95167D01*
X303153Y-95417D01*
X301633D01*
G01X306860Y-97667D02*
X309140Y-92500D01*
G01X311643Y-97500D02*
Y-92500D01*
X314557Y-97500D01*
Y-92500D01*
G01X318200Y-97667D02*
X318073Y-97583D01*
Y-97417D01*
X318200Y-97333D01*
X318327Y-97417D01*
Y-97583D01*
X318200Y-97667D01*
G01Y-95417D02*
X318073Y-95333D01*
Y-95167D01*
X318200Y-95083D01*
X318327Y-95167D01*
Y-95333D01*
X318200Y-95417D01*
G01X296000Y-112500D02*
X496000D01*
G01X301633Y-72500D02*
Y-67500D01*
X303153D01*
X303660Y-67750D01*
X304040Y-68333D01*
X304167Y-69000D01*
X304040Y-69667D01*
X303723Y-70167D01*
X303153Y-70417D01*
X301633D01*
G01X306733Y-72500D02*
Y-67500D01*
X308317D01*
X308823Y-67750D01*
X309140Y-68083D01*
X309267Y-68750D01*
X309140Y-69417D01*
X308760Y-69833D01*
X308317Y-70083D01*
X306733D01*
G01X308317D02*
X309267Y-72500D01*
G01X313100D02*
X312593Y-72417D01*
X312150Y-72083D01*
X311770Y-71583D01*
X311517Y-71000D01*
X311390Y-70333D01*
Y-69667D01*
X311517Y-69000D01*
X311770Y-68417D01*
X312150Y-67917D01*
X312593Y-67583D01*
X313100Y-67500D01*
X313607Y-67583D01*
X314050Y-67917D01*
X314430Y-68417D01*
X314683Y-69000D01*
X314810Y-69667D01*
Y-70333D01*
X314683Y-71000D01*
X314430Y-71583D01*
X314050Y-72083D01*
X313607Y-72417D01*
X313100Y-72500D01*
G01X316933Y-71500D02*
X317250Y-72000D01*
X317630Y-72333D01*
X318073Y-72500D01*
X318580Y-72333D01*
X318960Y-72000D01*
X319340Y-71500D01*
X319467Y-70833D01*
Y-67500D01*
G01X324567Y-72500D02*
X322033D01*
Y-67500D01*
X324567D01*
G01X323553Y-69917D02*
X322033D01*
G01X329793Y-67917D02*
X329413Y-67667D01*
X328970Y-67500D01*
X328463D01*
X327893Y-67750D01*
X327450Y-68167D01*
X327133Y-68667D01*
X326880Y-69500D01*
X326817Y-70250D01*
X326943Y-71000D01*
X327133Y-71500D01*
X327513Y-72000D01*
X327957Y-72333D01*
X328400Y-72500D01*
X328843D01*
X329287Y-72333D01*
X329667Y-72083D01*
X329983Y-71750D01*
G01X333500Y-67500D02*
Y-72500D01*
G01X332043Y-67500D02*
X334957D01*
G01X338600Y-72667D02*
X338473Y-72583D01*
Y-72417D01*
X338600Y-72333D01*
X338727Y-72417D01*
Y-72583D01*
X338600Y-72667D01*
G01Y-70417D02*
X338473Y-70333D01*
Y-70167D01*
X338600Y-70083D01*
X338727Y-70167D01*
Y-70333D01*
X338600Y-70417D01*
G01X296000Y-87500D02*
X496000D01*
G01X317323Y1881102D02*
G02X296850I-10237J0D01*
G01Y1885039D01*
G02X317323I10236J0D01*
G01Y1881102D01*
G01Y1885039D02*
Y1881102D01*
G02X296850I-10237J0D01*
G01Y1885039D01*
G02X317323I10236J0D01*
G01X411000Y-112500D02*
Y-137500D01*
G01X416633Y-122500D02*
Y-117500D01*
X418217D01*
X418723Y-117750D01*
X419040Y-118083D01*
X419167Y-118750D01*
X419040Y-119417D01*
X418660Y-119833D01*
X418217Y-120083D01*
X416633D01*
G01X418217D02*
X419167Y-122500D01*
G01X424267D02*
X421733D01*
Y-117500D01*
X424267D01*
G01X423253Y-119917D02*
X421733D01*
G01X426517Y-117500D02*
X428100Y-122500D01*
X429683Y-117500D01*
G01X433200Y-122667D02*
X433073Y-122583D01*
Y-122417D01*
X433200Y-122333D01*
X433327Y-122417D01*
Y-122583D01*
X433200Y-122667D01*
G01Y-120417D02*
X433073Y-120333D01*
Y-120167D01*
X433200Y-120083D01*
X433327Y-120167D01*
Y-120333D01*
X433200Y-120417D01*
G01X460000Y-112500D02*
Y-137500D01*
G01X-723776Y2987387D02*
Y-376795D01*
Y-489221D01*
X1782976D01*
Y-376795D01*
Y2987387D01*
X-723776D01*
G01X47633Y1053821D02*
X-11619D01*
Y678900D01*
X47633D01*
Y1053821D01*
G01X16471Y690711D02*
X192D01*
Y1042010D01*
X35822D01*
G01X47637Y1412086D02*
X-11615D01*
Y1037165D01*
X47637D01*
Y1412086D01*
G01X16475Y1048976D02*
X196D01*
Y1400275D01*
X35826D01*
G01X6705Y-124160D02*
X7332Y-124685D01*
X8037Y-125000D01*
X8663D01*
X9290Y-124685D01*
X9760Y-124160D01*
X9995Y-123425D01*
X9838Y-122690D01*
X9447Y-122060D01*
X8742Y-121640D01*
X7802Y-121430D01*
X7253Y-121010D01*
X7018Y-120275D01*
X7175Y-119540D01*
X7567Y-119015D01*
X8115Y-118700D01*
X8663D01*
X9212Y-118910D01*
X9682Y-119435D01*
G01X13005Y-125000D02*
Y-118700D01*
G01X16295D02*
Y-125000D01*
G01Y-121850D02*
X13005D01*
G01X20010Y-118700D02*
X21890D01*
G01X20950D02*
Y-125000D01*
G01X20010D02*
X21890D01*
G01X28817D02*
X25683D01*
Y-118700D01*
X28817D01*
G01X27563Y-121745D02*
X25683D01*
G01X31748Y-125000D02*
Y-118700D01*
X35352Y-125000D01*
Y-118700D01*
G01X39693Y-126155D02*
X40007Y-124790D01*
G01X46150Y-118700D02*
Y-125000D01*
G01X44348Y-118700D02*
X47952D01*
G01X50492Y-125000D02*
X52450Y-118700D01*
X54408Y-125000D01*
G01X53703Y-122795D02*
X51197D01*
G01X57810Y-118700D02*
X59690D01*
G01X58750D02*
Y-125000D01*
G01X57810D02*
X59690D01*
G01X62700Y-118700D02*
X63797Y-125000D01*
X65050Y-118700D01*
X66303Y-125000D01*
X67400Y-118700D01*
G01X69392Y-125000D02*
X71350Y-118700D01*
X73308Y-125000D01*
G01X72603Y-122795D02*
X70097D01*
G01X75848Y-125000D02*
Y-118700D01*
X79452Y-125000D01*
Y-118700D01*
G01X88683Y-125000D02*
Y-118700D01*
X90642D01*
X91268Y-119015D01*
X91660Y-119435D01*
X91817Y-120275D01*
X91660Y-121115D01*
X91190Y-121640D01*
X90642Y-121955D01*
X88683D01*
G01X90642D02*
X91817Y-125000D01*
G01X96550Y-125210D02*
X96393Y-125105D01*
Y-124895D01*
X96550Y-124790D01*
X96707Y-124895D01*
Y-125105D01*
X96550Y-125210D01*
G01X102850Y-125000D02*
X102223Y-124895D01*
X101675Y-124475D01*
X101205Y-123845D01*
X100892Y-123110D01*
X100735Y-122270D01*
Y-121430D01*
X100892Y-120590D01*
X101205Y-119855D01*
X101675Y-119225D01*
X102223Y-118805D01*
X102850Y-118700D01*
X103477Y-118805D01*
X104025Y-119225D01*
X104495Y-119855D01*
X104808Y-120590D01*
X104965Y-121430D01*
Y-122270D01*
X104808Y-123110D01*
X104495Y-123845D01*
X104025Y-124475D01*
X103477Y-124895D01*
X102850Y-125000D01*
G01X109150Y-125210D02*
X108993Y-125105D01*
Y-124895D01*
X109150Y-124790D01*
X109307Y-124895D01*
Y-125105D01*
X109150Y-125210D01*
G01X117173Y-119225D02*
X116703Y-118910D01*
X116155Y-118700D01*
X115528D01*
X114823Y-119015D01*
X114275Y-119540D01*
X113883Y-120170D01*
X113570Y-121220D01*
X113492Y-122165D01*
X113648Y-123110D01*
X113883Y-123740D01*
X114353Y-124370D01*
X114902Y-124790D01*
X115450Y-125000D01*
X115998D01*
X116547Y-124790D01*
X117017Y-124475D01*
X117408Y-124055D01*
G01X121750Y-125210D02*
X121593Y-125105D01*
Y-124895D01*
X121750Y-124790D01*
X121907Y-124895D01*
Y-125105D01*
X121750Y-125210D01*
G01X6627Y-115000D02*
Y-108700D01*
G01X9603D02*
X6627Y-112585D01*
G01X10073Y-115000D02*
X7958Y-110800D01*
G01X12927Y-108700D02*
Y-113215D01*
X13240Y-114160D01*
X13867Y-114790D01*
X14650Y-115000D01*
X15433Y-114790D01*
X16060Y-114160D01*
X16373Y-113215D01*
Y-108700D01*
G01X22517Y-115000D02*
X19383D01*
Y-108700D01*
X22517D01*
G01X21263Y-111745D02*
X19383D01*
G01X26310Y-108700D02*
X28190D01*
G01X27250D02*
Y-115000D01*
G01X26310D02*
X28190D01*
G01X38205Y-114160D02*
X38832Y-114685D01*
X39537Y-115000D01*
X40163D01*
X40790Y-114685D01*
X41260Y-114160D01*
X41495Y-113425D01*
X41338Y-112690D01*
X40947Y-112060D01*
X40242Y-111640D01*
X39302Y-111430D01*
X38753Y-111010D01*
X38518Y-110275D01*
X38675Y-109540D01*
X39067Y-109015D01*
X39615Y-108700D01*
X40163D01*
X40712Y-108910D01*
X41182Y-109435D01*
G01X44505Y-115000D02*
Y-108700D01*
G01X47795D02*
Y-115000D01*
G01Y-111850D02*
X44505D01*
G01X50492Y-115000D02*
X52450Y-108700D01*
X54408Y-115000D01*
G01X53703Y-112795D02*
X51197D01*
G01X56948Y-115000D02*
Y-108700D01*
X60552Y-115000D01*
Y-108700D01*
G01X69705Y-115000D02*
Y-108700D01*
G01X72995D02*
Y-115000D01*
G01Y-111850D02*
X69705D01*
G01X76005Y-114160D02*
X76632Y-114685D01*
X77337Y-115000D01*
X77963D01*
X78590Y-114685D01*
X79060Y-114160D01*
X79295Y-113425D01*
X79138Y-112690D01*
X78747Y-112060D01*
X78042Y-111640D01*
X77102Y-111430D01*
X76553Y-111010D01*
X76318Y-110275D01*
X76475Y-109540D01*
X76867Y-109015D01*
X77415Y-108700D01*
X77963D01*
X78512Y-108910D01*
X78982Y-109435D01*
G01X83010Y-108700D02*
X84890D01*
G01X83950D02*
Y-115000D01*
G01X83010D02*
X84890D01*
G01X88292D02*
X90250Y-108700D01*
X92208Y-115000D01*
G01X91503Y-112795D02*
X88997D01*
G01X94748Y-115000D02*
Y-108700D01*
X98352Y-115000D01*
Y-108700D01*
G01X103320Y-111850D02*
X104887D01*
Y-113740D01*
X104417Y-114370D01*
X103868Y-114790D01*
X103085Y-115000D01*
X102302Y-114790D01*
X101753Y-114370D01*
X101283Y-113740D01*
X100970Y-113005D01*
X100813Y-112165D01*
Y-111430D01*
X100970Y-110800D01*
X101283Y-110065D01*
X101753Y-109435D01*
X102223Y-109015D01*
X102850Y-108700D01*
X103398D01*
X104025Y-108910D01*
X104495Y-109330D01*
G01X108993Y-116155D02*
X109307Y-114790D01*
G01X115450Y-108700D02*
Y-115000D01*
G01X113648Y-108700D02*
X117252D01*
G01X119792Y-115000D02*
X121750Y-108700D01*
X123708Y-115000D01*
G01X123003Y-112795D02*
X120497D01*
G01X128050Y-115000D02*
X127423Y-114895D01*
X126875Y-114475D01*
X126405Y-113845D01*
X126092Y-113110D01*
X125935Y-112270D01*
Y-111430D01*
X126092Y-110590D01*
X126405Y-109855D01*
X126875Y-109225D01*
X127423Y-108805D01*
X128050Y-108700D01*
X128677Y-108805D01*
X129225Y-109225D01*
X129695Y-109855D01*
X130008Y-110590D01*
X130165Y-111430D01*
Y-112270D01*
X130008Y-113110D01*
X129695Y-113845D01*
X129225Y-114475D01*
X128677Y-114895D01*
X128050Y-115000D01*
G01X140650D02*
Y-112165D01*
X139083Y-108700D01*
G01X142217D02*
X140650Y-112165D01*
G01X145227Y-108700D02*
Y-113215D01*
X145540Y-114160D01*
X146167Y-114790D01*
X146950Y-115000D01*
X147733Y-114790D01*
X148360Y-114160D01*
X148673Y-113215D01*
Y-108700D01*
G01X151292Y-115000D02*
X153250Y-108700D01*
X155208Y-115000D01*
G01X154503Y-112795D02*
X151997D01*
G01X157748Y-115000D02*
Y-108700D01*
X161352Y-115000D01*
Y-108700D01*
G01X30650Y-92300D02*
X28130Y-91883D01*
X25925Y-90217D01*
X24035Y-87717D01*
X22775Y-84800D01*
X22145Y-81467D01*
Y-78133D01*
X22775Y-74800D01*
X24035Y-71883D01*
X25925Y-69384D01*
X28130Y-67717D01*
X30650Y-67300D01*
X33170Y-67717D01*
X35375Y-69384D01*
X37265Y-71883D01*
X38525Y-74800D01*
X39155Y-78133D01*
Y-81467D01*
X38525Y-84800D01*
X37265Y-87717D01*
X35375Y-90217D01*
X33170Y-91883D01*
X30650Y-92300D01*
G01X33170Y-85633D02*
X36950Y-92300D01*
G01X50495Y-75634D02*
Y-87300D01*
X51755Y-90217D01*
X53645Y-91883D01*
X55850Y-92300D01*
X58055Y-91883D01*
X59945Y-90217D01*
X61205Y-87300D01*
G01Y-92300D02*
Y-75634D01*
G01X86720Y-92300D02*
Y-75634D01*
G01Y-78550D02*
X85460Y-76884D01*
X83570Y-76050D01*
X81365Y-75634D01*
X79160Y-76467D01*
X77270Y-78133D01*
X76010Y-80634D01*
X75380Y-83967D01*
X76010Y-87300D01*
X77270Y-89801D01*
X79160Y-91467D01*
X81365Y-92300D01*
X83570Y-91883D01*
X85460Y-90634D01*
X86720Y-88967D01*
G01X100895Y-92300D02*
Y-75634D01*
G01Y-79800D02*
X102155Y-77717D01*
X104045Y-76050D01*
X106565Y-75634D01*
X108770Y-76050D01*
X110660Y-77717D01*
X111605Y-80634D01*
Y-92300D01*
G01X131450Y-67300D02*
Y-92300D01*
G01X127040Y-75634D02*
X135860D01*
G01X162320Y-92300D02*
Y-75634D01*
G01Y-78550D02*
X161060Y-76884D01*
X159170Y-76050D01*
X156965Y-75634D01*
X154760Y-76467D01*
X152870Y-78133D01*
X151610Y-80634D01*
X150980Y-83967D01*
X151610Y-87300D01*
X152870Y-89801D01*
X154760Y-91467D01*
X156965Y-92300D01*
X159170Y-91883D01*
X161060Y-90634D01*
X162320Y-88967D01*
G01X6548Y-105000D02*
Y-98700D01*
X10152Y-105000D01*
Y-98700D01*
G01X14650Y-105000D02*
X14023Y-104895D01*
X13475Y-104475D01*
X13005Y-103845D01*
X12692Y-103110D01*
X12535Y-102270D01*
Y-101430D01*
X12692Y-100590D01*
X13005Y-99855D01*
X13475Y-99225D01*
X14023Y-98805D01*
X14650Y-98700D01*
X15277Y-98805D01*
X15825Y-99225D01*
X16295Y-99855D01*
X16608Y-100590D01*
X16765Y-101430D01*
Y-102270D01*
X16608Y-103110D01*
X16295Y-103845D01*
X15825Y-104475D01*
X15277Y-104895D01*
X14650Y-105000D01*
G01X20950Y-105210D02*
X20793Y-105105D01*
Y-104895D01*
X20950Y-104790D01*
X21107Y-104895D01*
Y-105105D01*
X20950Y-105210D01*
G01X27250Y-105000D02*
Y-98700D01*
X26310Y-99960D01*
G01Y-105000D02*
X28190D01*
G01X33550D02*
X34098Y-104895D01*
X34725Y-104580D01*
X35117Y-104055D01*
X35273Y-103320D01*
X35117Y-102585D01*
X34647Y-101955D01*
X33942Y-101640D01*
X33158D01*
X32688Y-101430D01*
X32297Y-100905D01*
X32140Y-100170D01*
X32375Y-99435D01*
X32923Y-98910D01*
X33550Y-98700D01*
X34177Y-98910D01*
X34725Y-99435D01*
X34960Y-100170D01*
X34803Y-100905D01*
X34412Y-101430D01*
X33942Y-101640D01*
X33158D01*
X32453Y-101955D01*
X31983Y-102585D01*
X31827Y-103320D01*
X31983Y-104055D01*
X32375Y-104580D01*
X33002Y-104895D01*
X33550Y-105000D01*
G01X39850D02*
X40398Y-104895D01*
X41025Y-104580D01*
X41417Y-104055D01*
X41573Y-103320D01*
X41417Y-102585D01*
X40947Y-101955D01*
X40242Y-101640D01*
X39458D01*
X38988Y-101430D01*
X38597Y-100905D01*
X38440Y-100170D01*
X38675Y-99435D01*
X39223Y-98910D01*
X39850Y-98700D01*
X40477Y-98910D01*
X41025Y-99435D01*
X41260Y-100170D01*
X41103Y-100905D01*
X40712Y-101430D01*
X40242Y-101640D01*
X39458D01*
X38753Y-101955D01*
X38283Y-102585D01*
X38127Y-103320D01*
X38283Y-104055D01*
X38675Y-104580D01*
X39302Y-104895D01*
X39850Y-105000D01*
G01X45993Y-106155D02*
X46307Y-104790D01*
G01X50100Y-98700D02*
X51197Y-105000D01*
X52450Y-98700D01*
X53703Y-105000D01*
X54800Y-98700D01*
G01X60317Y-105000D02*
X57183D01*
Y-98700D01*
X60317D01*
G01X59063Y-101745D02*
X57183D01*
G01X63248Y-105000D02*
Y-98700D01*
X66852Y-105000D01*
Y-98700D01*
G01X76005Y-105000D02*
Y-98700D01*
G01X79295D02*
Y-105000D01*
G01Y-101850D02*
X76005D01*
G01X81600Y-98700D02*
X82697Y-105000D01*
X83950Y-98700D01*
X85203Y-105000D01*
X86300Y-98700D01*
G01X88292Y-105000D02*
X90250Y-98700D01*
X92208Y-105000D01*
G01X91503Y-102795D02*
X88997D01*
G01X101362Y-99750D02*
X101832Y-99120D01*
X102380Y-98805D01*
X103007Y-98700D01*
X103790Y-98910D01*
X104338Y-99435D01*
X104495Y-100065D01*
X104417Y-100695D01*
X104103Y-101220D01*
X102537Y-102270D01*
X101832Y-103005D01*
X101362Y-104055D01*
X101205Y-105000D01*
X104495D01*
G01X107348D02*
Y-98700D01*
X110952Y-105000D01*
Y-98700D01*
G01X113727Y-105000D02*
Y-98700D01*
X115293D01*
X115920Y-99015D01*
X116390Y-99435D01*
X116782Y-100065D01*
X117095Y-100800D01*
X117173Y-101850D01*
X117095Y-102900D01*
X116782Y-103635D01*
X116390Y-104265D01*
X115920Y-104685D01*
X115293Y-105000D01*
X113727D01*
G01X126483D02*
Y-98700D01*
X128442D01*
X129068Y-99015D01*
X129460Y-99435D01*
X129617Y-100275D01*
X129460Y-101115D01*
X128990Y-101640D01*
X128442Y-101955D01*
X126483D01*
G01X128442D02*
X129617Y-105000D01*
G01X132627D02*
Y-98700D01*
X134193D01*
X134820Y-99015D01*
X135290Y-99435D01*
X135682Y-100065D01*
X135995Y-100800D01*
X136073Y-101850D01*
X135995Y-102900D01*
X135682Y-103635D01*
X135290Y-104265D01*
X134820Y-104685D01*
X134193Y-105000D01*
X132627D01*
G01X140650Y-105210D02*
X140493Y-105105D01*
Y-104895D01*
X140650Y-104790D01*
X140807Y-104895D01*
Y-105105D01*
X140650Y-105210D01*
G01X4467Y22232D02*
Y83768D01*
X69979D01*
Y22232D01*
X4467D01*
G01X26756Y138720D02*
X15276D01*
Y124842D01*
X10551D01*
Y114605D01*
X15276D01*
Y100727D01*
X26756D01*
G01X15539Y140516D02*
X15731Y140206D01*
X15961Y139999D01*
X16229Y139896D01*
X16536Y139999D01*
X16766Y140206D01*
X16996Y140516D01*
X17073Y140929D01*
Y142996D01*
G01X18563Y140516D02*
X18793Y140154D01*
X19099Y139948D01*
X19444Y139896D01*
X19751Y139948D01*
X20058Y140206D01*
X20249Y140516D01*
X20288Y140826D01*
X20211Y141188D01*
X19943Y141446D01*
X19674Y141549D01*
X19329D01*
G01X19674D02*
X19904Y141704D01*
X20096Y141963D01*
X20173Y142273D01*
X20096Y142583D01*
X19904Y142841D01*
X19559Y142996D01*
X19214Y142944D01*
X18869Y142738D01*
G01X21663Y140516D02*
X21893Y140154D01*
X22199Y139948D01*
X22544Y139896D01*
X22851Y139948D01*
X23158Y140206D01*
X23349Y140516D01*
X23388Y140826D01*
X23311Y141188D01*
X23043Y141446D01*
X22774Y141549D01*
X22429D01*
G01X22774D02*
X23004Y141704D01*
X23196Y141963D01*
X23273Y142273D01*
X23196Y142583D01*
X23004Y142841D01*
X22659Y142996D01*
X22314Y142944D01*
X21969Y142738D01*
G01X4467Y158232D02*
Y219768D01*
X69979D01*
Y158232D01*
X4467D01*
G01Y231232D02*
Y292768D01*
X69979D01*
Y231232D01*
X4467D01*
G01X13393Y315995D02*
X13755Y316225D01*
X13961Y316531D01*
X14013Y316876D01*
X13961Y317183D01*
X13703Y317490D01*
X13393Y317681D01*
X13083Y317720D01*
X12721Y317643D01*
X12463Y317375D01*
X12360Y317106D01*
Y316761D01*
G01Y317106D02*
X12205Y317336D01*
X11946Y317528D01*
X11636Y317605D01*
X11326Y317528D01*
X11068Y317336D01*
X10913Y316991D01*
X10965Y316646D01*
X11171Y316301D01*
G01X26480Y353551D02*
X15000D01*
Y333767D01*
X10275D01*
Y323531D01*
X15000D01*
Y303747D01*
X26480D01*
G01X4467Y367232D02*
Y428768D01*
X69979D01*
Y367232D01*
X4467D01*
G01X14963Y355547D02*
X15155Y355237D01*
X15385Y355030D01*
X15653Y354927D01*
X15960Y355030D01*
X16190Y355237D01*
X16420Y355547D01*
X16497Y355960D01*
Y358027D01*
G01X17987Y355547D02*
X18217Y355185D01*
X18523Y354979D01*
X18868Y354927D01*
X19175Y354979D01*
X19482Y355237D01*
X19673Y355547D01*
X19712Y355857D01*
X19635Y356219D01*
X19367Y356477D01*
X19098Y356580D01*
X18753D01*
G01X19098D02*
X19328Y356735D01*
X19520Y356994D01*
X19597Y357304D01*
X19520Y357614D01*
X19328Y357872D01*
X18983Y358027D01*
X18638Y357975D01*
X18293Y357769D01*
G01X22390Y354927D02*
Y358027D01*
X20972Y355805D01*
X22888D01*
G01X24510Y438542D02*
X18210D01*
Y440501D01*
X18525Y441127D01*
X18945Y441519D01*
X19785Y441676D01*
X20625Y441519D01*
X21150Y441049D01*
X21465Y440501D01*
Y438542D01*
G01Y440501D02*
X24510Y441676D01*
G01Y447976D02*
Y444842D01*
X18210D01*
Y447976D01*
G01X21255Y446722D02*
Y444842D01*
G01X18210Y450751D02*
X24510Y452709D01*
X18210Y454667D01*
G01Y463742D02*
X24510D01*
Y466876D01*
G01Y469651D02*
X18210Y471609D01*
X24510Y473567D01*
G01X22305Y472862D02*
Y470356D01*
G01X21150Y478536D02*
X20835Y478849D01*
X20310Y479084D01*
X19575Y479241D01*
X18945Y479084D01*
X18525Y478771D01*
X18210Y478222D01*
Y476107D01*
X24510D01*
Y478692D01*
X24090Y479241D01*
X23460Y479554D01*
X22725Y479711D01*
X21990Y479554D01*
X21360Y479084D01*
X21150Y478536D01*
Y476107D01*
G01X24510Y485776D02*
Y482642D01*
X18210D01*
Y485776D01*
G01X21255Y484522D02*
Y482642D01*
G01X18210Y488942D02*
X24510D01*
Y492076D01*
G01X11757Y431344D02*
Y494336D01*
X31442D01*
Y431344D01*
X11757D01*
G01X10201Y492375D02*
X7101D01*
Y493334D01*
X7256Y493640D01*
X7463Y493832D01*
X7876Y493909D01*
X8289Y493832D01*
X8548Y493602D01*
X8703Y493334D01*
Y492375D01*
G01Y493334D02*
X10201Y493909D01*
G01Y496242D02*
X7101D01*
X7721Y495782D01*
G01X10201D02*
Y496702D01*
G01X9736Y498499D02*
X9994Y498729D01*
X10149Y498997D01*
X10201Y499342D01*
X10098Y499687D01*
X9891Y499955D01*
X9529Y500147D01*
X9116Y500185D01*
X8703Y500109D01*
X8444Y499917D01*
X8238Y499649D01*
X8186Y499380D01*
X8238Y499112D01*
X8444Y498767D01*
X7101Y498882D01*
Y499917D01*
G01Y502442D02*
X7204Y502135D01*
X7463Y501905D01*
X7773Y501752D01*
X8186Y501637D01*
X8651Y501599D01*
X9116Y501637D01*
X9529Y501752D01*
X9839Y501905D01*
X10098Y502135D01*
X10201Y502442D01*
X10098Y502749D01*
X9839Y502979D01*
X9529Y503132D01*
X9116Y503247D01*
X8651Y503285D01*
X8186Y503247D01*
X7773Y503132D01*
X7463Y502979D01*
X7204Y502749D01*
X7101Y502442D01*
G01X15041Y503440D02*
Y497240D01*
X11841D01*
Y503440D01*
X15041D01*
G01X40354Y504717D02*
X4467D01*
G01D02*
Y569283D01*
X40354D01*
G01X28070Y587134D02*
X23070Y589794D01*
G01Y587134D02*
X28070Y589794D01*
G01Y593564D02*
X27987Y594007D01*
X27737Y594514D01*
X27320Y594831D01*
X26737Y594957D01*
X26153Y594831D01*
X25653Y594451D01*
X25403Y593881D01*
Y593247D01*
X25237Y592867D01*
X24820Y592551D01*
X24237Y592424D01*
X23653Y592614D01*
X23237Y593057D01*
X23070Y593564D01*
X23237Y594071D01*
X23653Y594514D01*
X24237Y594704D01*
X24820Y594577D01*
X25237Y594261D01*
X25403Y593881D01*
Y593247D01*
X25653Y592677D01*
X26153Y592297D01*
X26737Y592171D01*
X27320Y592297D01*
X27737Y592614D01*
X27987Y593121D01*
X28070Y593564D01*
G01X27487Y597587D02*
X27903Y598031D01*
X28070Y598537D01*
X27903Y599044D01*
X27403Y599487D01*
X26653Y599804D01*
X25903Y599931D01*
X24987D01*
X24237Y599804D01*
X23570Y599487D01*
X23237Y599107D01*
X23070Y598664D01*
X23237Y598157D01*
X23570Y597777D01*
X24070Y597524D01*
X24737Y597397D01*
X25320Y597524D01*
X25903Y597841D01*
X26237Y598221D01*
X26320Y598664D01*
X26153Y599171D01*
X25737Y599551D01*
X24987Y599931D01*
G01X23903Y602561D02*
X23403Y602941D01*
X23153Y603384D01*
X23070Y603891D01*
X23237Y604524D01*
X23653Y604967D01*
X24153Y605094D01*
X24653Y605031D01*
X25070Y604777D01*
X25903Y603511D01*
X26487Y602941D01*
X27320Y602561D01*
X28070Y602434D01*
Y605094D01*
G01X23903Y607661D02*
X23403Y608041D01*
X23153Y608484D01*
X23070Y608991D01*
X23237Y609624D01*
X23653Y610067D01*
X24153Y610194D01*
X24653Y610131D01*
X25070Y609877D01*
X25903Y608611D01*
X26487Y608041D01*
X27320Y607661D01*
X28070Y607534D01*
Y610194D01*
G01X27320Y612571D02*
X27737Y612951D01*
X27987Y613394D01*
X28070Y613964D01*
X27903Y614534D01*
X27570Y614977D01*
X26987Y615294D01*
X26320Y615357D01*
X25653Y615231D01*
X25237Y614914D01*
X24903Y614471D01*
X24820Y614027D01*
X24903Y613584D01*
X25237Y613014D01*
X23070Y613204D01*
Y614914D01*
G01X28070Y618937D02*
X26987Y619064D01*
X26070Y619254D01*
X25237Y619507D01*
X24320Y619824D01*
X23070Y620331D01*
Y617797D01*
G01X26403Y623341D02*
Y624987D01*
G01X23070Y629264D02*
X23237Y628757D01*
X23653Y628377D01*
X24153Y628124D01*
X24820Y627934D01*
X25570Y627871D01*
X26320Y627934D01*
X26987Y628124D01*
X27487Y628377D01*
X27903Y628757D01*
X28070Y629264D01*
X27903Y629771D01*
X27487Y630151D01*
X26987Y630404D01*
X26320Y630594D01*
X25570Y630657D01*
X24820Y630594D01*
X24153Y630404D01*
X23653Y630151D01*
X23237Y629771D01*
X23070Y629264D01*
G01Y634364D02*
X23237Y633857D01*
X23653Y633477D01*
X24153Y633224D01*
X24820Y633034D01*
X25570Y632971D01*
X26320Y633034D01*
X26987Y633224D01*
X27487Y633477D01*
X27903Y633857D01*
X28070Y634364D01*
X27903Y634871D01*
X27487Y635251D01*
X26987Y635504D01*
X26320Y635694D01*
X25570Y635757D01*
X24820Y635694D01*
X24153Y635504D01*
X23653Y635251D01*
X23237Y634871D01*
X23070Y634364D01*
G01X28070Y639464D02*
X23070D01*
X24070Y638704D01*
G01X28070D02*
Y640224D01*
G01X7633Y570781D02*
X4533D01*
Y571740D01*
X4688Y572046D01*
X4895Y572238D01*
X5308Y572315D01*
X5721Y572238D01*
X5980Y572008D01*
X6135Y571740D01*
Y570781D01*
G01Y571740D02*
X7633Y572315D01*
G01Y574648D02*
X4533D01*
X5153Y574188D01*
G01X7633D02*
Y575108D01*
G01Y578208D02*
X4533D01*
X6755Y576790D01*
Y578706D01*
G01X7633Y580848D02*
X7581Y581116D01*
X7426Y581423D01*
X7168Y581615D01*
X6806Y581691D01*
X6445Y581615D01*
X6135Y581385D01*
X5980Y581040D01*
Y580656D01*
X5876Y580426D01*
X5618Y580235D01*
X5256Y580158D01*
X4895Y580273D01*
X4636Y580541D01*
X4533Y580848D01*
X4636Y581155D01*
X4895Y581423D01*
X5256Y581538D01*
X5618Y581461D01*
X5876Y581270D01*
X5980Y581040D01*
Y580656D01*
X6135Y580311D01*
X6445Y580081D01*
X6806Y580005D01*
X7168Y580081D01*
X7426Y580273D01*
X7581Y580580D01*
X7633Y580848D01*
G01X12514Y577736D02*
Y571536D01*
X9314D01*
Y577736D01*
X12514D01*
G01X22408Y570387D02*
X19308D01*
Y571346D01*
X19463Y571652D01*
X19670Y571844D01*
X20083Y571921D01*
X20496Y571844D01*
X20755Y571614D01*
X20910Y571346D01*
Y570387D01*
G01Y571346D02*
X22408Y571921D01*
G01Y574254D02*
X19308D01*
X19928Y573794D01*
G01X22408D02*
Y574714D01*
G01Y577814D02*
X19308D01*
X21530Y576396D01*
Y578312D01*
G01X22046Y579802D02*
X22305Y580071D01*
X22408Y580377D01*
X22305Y580684D01*
X21995Y580952D01*
X21530Y581144D01*
X21065Y581221D01*
X20496D01*
X20031Y581144D01*
X19618Y580952D01*
X19411Y580722D01*
X19308Y580454D01*
X19411Y580147D01*
X19618Y579917D01*
X19928Y579764D01*
X20341Y579687D01*
X20703Y579764D01*
X21065Y579956D01*
X21271Y580186D01*
X21323Y580454D01*
X21220Y580761D01*
X20961Y580991D01*
X20496Y581221D01*
G01X17584Y577802D02*
Y571602D01*
X14384D01*
Y577802D01*
X17584D01*
G01X27662Y650926D02*
X22662D01*
Y652510D01*
X22912Y653016D01*
X23245Y653333D01*
X23912Y653460D01*
X24579Y653333D01*
X24995Y652953D01*
X25245Y652510D01*
Y650926D01*
G01Y652510D02*
X27662Y653460D01*
G01X25412Y656343D02*
Y658370D01*
X24829Y658180D01*
X24495Y657863D01*
X24329Y657420D01*
X24412Y656976D01*
X24662Y656596D01*
X25245Y656343D01*
X25745Y656216D01*
X26245D01*
X26745Y656343D01*
X27245Y656660D01*
X27579Y657040D01*
X27662Y657483D01*
X27495Y657926D01*
X26995Y658370D01*
G01X24329Y661253D02*
X27662Y662393D01*
X24329Y663533D01*
G01X27662Y671010D02*
X22662Y672593D01*
X27662Y674176D01*
G01X25912Y673606D02*
Y671580D01*
G01X7386Y682489D02*
X7231Y682642D01*
X6972Y682757D01*
X6611Y682834D01*
X6301Y682757D01*
X6094Y682604D01*
X5939Y682335D01*
Y681300D01*
X9039D01*
Y682565D01*
X8832Y682834D01*
X8522Y682987D01*
X8161Y683064D01*
X7799Y682987D01*
X7489Y682757D01*
X7386Y682489D01*
Y681300D01*
G01X9039Y685282D02*
X8987Y685550D01*
X8832Y685857D01*
X8574Y686049D01*
X8212Y686125D01*
X7851Y686049D01*
X7541Y685819D01*
X7386Y685474D01*
Y685090D01*
X7282Y684860D01*
X7024Y684669D01*
X6662Y684592D01*
X6301Y684707D01*
X6042Y684975D01*
X5939Y685282D01*
X6042Y685589D01*
X6301Y685857D01*
X6662Y685972D01*
X7024Y685895D01*
X7282Y685704D01*
X7386Y685474D01*
Y685090D01*
X7541Y684745D01*
X7851Y684515D01*
X8212Y684439D01*
X8574Y684515D01*
X8832Y684707D01*
X8987Y685014D01*
X9039Y685282D01*
G01X6456Y687654D02*
X6146Y687884D01*
X5991Y688152D01*
X5939Y688459D01*
X6042Y688842D01*
X6301Y689110D01*
X6611Y689187D01*
X6921Y689149D01*
X7179Y688995D01*
X7696Y688229D01*
X8057Y687884D01*
X8574Y687654D01*
X9039Y687577D01*
Y689187D01*
G01X15260Y682489D02*
X15105Y682642D01*
X14846Y682757D01*
X14485Y682834D01*
X14175Y682757D01*
X13968Y682604D01*
X13813Y682335D01*
Y681300D01*
X16913D01*
Y682565D01*
X16706Y682834D01*
X16396Y682987D01*
X16035Y683064D01*
X15673Y682987D01*
X15363Y682757D01*
X15260Y682489D01*
Y681300D01*
G01X16913Y685282D02*
X16861Y685550D01*
X16706Y685857D01*
X16448Y686049D01*
X16086Y686125D01*
X15725Y686049D01*
X15415Y685819D01*
X15260Y685474D01*
Y685090D01*
X15156Y684860D01*
X14898Y684669D01*
X14536Y684592D01*
X14175Y684707D01*
X13916Y684975D01*
X13813Y685282D01*
X13916Y685589D01*
X14175Y685857D01*
X14536Y685972D01*
X14898Y685895D01*
X15156Y685704D01*
X15260Y685474D01*
Y685090D01*
X15415Y684745D01*
X15725Y684515D01*
X16086Y684439D01*
X16448Y684515D01*
X16706Y684707D01*
X16861Y685014D01*
X16913Y685282D01*
G01Y688382D02*
X13813D01*
X14433Y687922D01*
G01X16913D02*
Y688842D01*
G01X26755Y681224D02*
X23655Y682182D01*
X26755Y683140D01*
G01X25670Y682795D02*
Y681569D01*
G01X26755Y685282D02*
X26703Y685550D01*
X26548Y685857D01*
X26290Y686049D01*
X25928Y686125D01*
X25567Y686049D01*
X25257Y685819D01*
X25102Y685474D01*
Y685090D01*
X24998Y684860D01*
X24740Y684669D01*
X24378Y684592D01*
X24017Y684707D01*
X23758Y684975D01*
X23655Y685282D01*
X23758Y685589D01*
X24017Y685857D01*
X24378Y685972D01*
X24740Y685895D01*
X24998Y685704D01*
X25102Y685474D01*
Y685090D01*
X25257Y684745D01*
X25567Y684515D01*
X25928Y684439D01*
X26290Y684515D01*
X26548Y684707D01*
X26703Y685014D01*
X26755Y685282D01*
G01Y688382D02*
X23655D01*
X24275Y687922D01*
G01X26755D02*
Y688842D01*
G01X35822Y1042010D02*
Y690711D01*
X24071D01*
G01X14652Y1035902D02*
X14497Y1036055D01*
X14238Y1036170D01*
X13877Y1036247D01*
X13567Y1036170D01*
X13360Y1036017D01*
X13205Y1035748D01*
Y1034713D01*
X16305D01*
Y1035978D01*
X16098Y1036247D01*
X15788Y1036400D01*
X15427Y1036477D01*
X15065Y1036400D01*
X14755Y1036170D01*
X14652Y1035902D01*
Y1034713D01*
G01X16305Y1038695D02*
X13205D01*
X13825Y1038235D01*
G01X16305D02*
Y1039155D01*
G01X27671Y1034651D02*
X24571Y1035609D01*
X27671Y1036567D01*
G01X26586Y1036222D02*
Y1034996D01*
G01X27671Y1038709D02*
X24571D01*
X25191Y1038249D01*
G01X27671D02*
Y1039169D01*
G01X8442Y1035585D02*
X8287Y1035738D01*
X8028Y1035853D01*
X7667Y1035930D01*
X7357Y1035853D01*
X7150Y1035700D01*
X6995Y1035431D01*
Y1034396D01*
X10095D01*
Y1035661D01*
X9888Y1035930D01*
X9578Y1036083D01*
X9217Y1036160D01*
X8855Y1036083D01*
X8545Y1035853D01*
X8442Y1035585D01*
Y1034396D01*
G01X7512Y1037650D02*
X7202Y1037880D01*
X7047Y1038148D01*
X6995Y1038455D01*
X7098Y1038838D01*
X7357Y1039106D01*
X7667Y1039183D01*
X7977Y1039145D01*
X8235Y1038991D01*
X8752Y1038225D01*
X9113Y1037880D01*
X9630Y1037650D01*
X10095Y1037573D01*
Y1039183D01*
G01X6662Y1052668D02*
X6507Y1052821D01*
X6248Y1052936D01*
X5887Y1053013D01*
X5577Y1052936D01*
X5370Y1052783D01*
X5215Y1052514D01*
Y1051479D01*
X8315D01*
Y1052744D01*
X8108Y1053013D01*
X7798Y1053166D01*
X7437Y1053243D01*
X7075Y1053166D01*
X6765Y1052936D01*
X6662Y1052668D01*
Y1051479D01*
G01X8315Y1055461D02*
X8263Y1055729D01*
X8108Y1056036D01*
X7850Y1056228D01*
X7488Y1056304D01*
X7127Y1056228D01*
X6817Y1055998D01*
X6662Y1055653D01*
Y1055269D01*
X6558Y1055039D01*
X6300Y1054848D01*
X5938Y1054771D01*
X5577Y1054886D01*
X5318Y1055154D01*
X5215Y1055461D01*
X5318Y1055768D01*
X5577Y1056036D01*
X5938Y1056151D01*
X6300Y1056074D01*
X6558Y1055883D01*
X6662Y1055653D01*
Y1055269D01*
X6817Y1054924D01*
X7127Y1054694D01*
X7488Y1054618D01*
X7850Y1054694D01*
X8108Y1054886D01*
X8263Y1055193D01*
X8315Y1055461D01*
G01X5732Y1057833D02*
X5422Y1058063D01*
X5267Y1058331D01*
X5215Y1058638D01*
X5318Y1059021D01*
X5577Y1059289D01*
X5887Y1059366D01*
X6197Y1059328D01*
X6455Y1059174D01*
X6972Y1058408D01*
X7333Y1058063D01*
X7850Y1057833D01*
X8315Y1057756D01*
Y1059366D01*
G01X12188Y1052405D02*
X12033Y1052558D01*
X11774Y1052673D01*
X11413Y1052750D01*
X11103Y1052673D01*
X10896Y1052520D01*
X10741Y1052251D01*
Y1051216D01*
X13841D01*
Y1052481D01*
X13634Y1052750D01*
X13324Y1052903D01*
X12963Y1052980D01*
X12601Y1052903D01*
X12291Y1052673D01*
X12188Y1052405D01*
Y1051216D01*
G01X13841Y1055198D02*
X13789Y1055466D01*
X13634Y1055773D01*
X13376Y1055965D01*
X13014Y1056041D01*
X12653Y1055965D01*
X12343Y1055735D01*
X12188Y1055390D01*
Y1055006D01*
X12084Y1054776D01*
X11826Y1054585D01*
X11464Y1054508D01*
X11103Y1054623D01*
X10844Y1054891D01*
X10741Y1055198D01*
X10844Y1055505D01*
X11103Y1055773D01*
X11464Y1055888D01*
X11826Y1055811D01*
X12084Y1055620D01*
X12188Y1055390D01*
Y1055006D01*
X12343Y1054661D01*
X12653Y1054431D01*
X13014Y1054355D01*
X13376Y1054431D01*
X13634Y1054623D01*
X13789Y1054930D01*
X13841Y1055198D01*
G01Y1058298D02*
X10741D01*
X11361Y1057838D01*
G01X13841D02*
Y1058758D01*
G01X35826Y1400275D02*
Y1048976D01*
X24075D01*
G01X16122Y1403536D02*
X15967Y1403689D01*
X15708Y1403804D01*
X15347Y1403881D01*
X15037Y1403804D01*
X14830Y1403651D01*
X14675Y1403382D01*
Y1402347D01*
X17775D01*
Y1403612D01*
X17568Y1403881D01*
X17258Y1404034D01*
X16897Y1404111D01*
X16535Y1404034D01*
X16225Y1403804D01*
X16122Y1403536D01*
Y1402347D01*
G01X17775Y1406329D02*
X14675D01*
X15295Y1405869D01*
G01X17775D02*
Y1406789D01*
G01X26433Y1403060D02*
X23333Y1404018D01*
X26433Y1404976D01*
G01X25348Y1404631D02*
Y1403405D01*
G01X26433Y1407118D02*
X23333D01*
X23953Y1406658D01*
G01X26433D02*
Y1407578D01*
G01X8248Y1403536D02*
X8093Y1403689D01*
X7834Y1403804D01*
X7473Y1403881D01*
X7163Y1403804D01*
X6956Y1403651D01*
X6801Y1403382D01*
Y1402347D01*
X9901D01*
Y1403612D01*
X9694Y1403881D01*
X9384Y1404034D01*
X9023Y1404111D01*
X8661Y1404034D01*
X8351Y1403804D01*
X8248Y1403536D01*
Y1402347D01*
G01X7318Y1405601D02*
X7008Y1405831D01*
X6853Y1406099D01*
X6801Y1406406D01*
X6904Y1406789D01*
X7163Y1407057D01*
X7473Y1407134D01*
X7783Y1407096D01*
X8041Y1406942D01*
X8558Y1406176D01*
X8919Y1405831D01*
X9436Y1405601D01*
X9901Y1405524D01*
Y1407134D01*
G01X18640Y1557028D02*
Y1560128D01*
X19599D01*
X19905Y1559973D01*
X20097Y1559766D01*
X20174Y1559353D01*
X20097Y1558940D01*
X19867Y1558681D01*
X19599Y1558526D01*
X18640D01*
G01X19599D02*
X20174Y1557028D01*
G01X22507D02*
Y1560128D01*
X22047Y1559508D01*
G01Y1557028D02*
X22967D01*
G01X24764Y1557493D02*
X24994Y1557235D01*
X25262Y1557080D01*
X25607Y1557028D01*
X25952Y1557131D01*
X26220Y1557338D01*
X26412Y1557700D01*
X26450Y1558113D01*
X26374Y1558526D01*
X26182Y1558785D01*
X25914Y1558991D01*
X25645Y1559043D01*
X25377Y1558991D01*
X25032Y1558785D01*
X25147Y1560128D01*
X26182D01*
G01X27864Y1557648D02*
X28094Y1557286D01*
X28400Y1557080D01*
X28745Y1557028D01*
X29052Y1557080D01*
X29359Y1557338D01*
X29550Y1557648D01*
X29589Y1557958D01*
X29512Y1558320D01*
X29244Y1558578D01*
X28975Y1558681D01*
X28630D01*
G01X28975D02*
X29205Y1558836D01*
X29397Y1559095D01*
X29474Y1559405D01*
X29397Y1559715D01*
X29205Y1559973D01*
X28860Y1560128D01*
X28515Y1560076D01*
X28170Y1559870D01*
G01X16216Y1557684D02*
X10016D01*
Y1560884D01*
X16216D01*
Y1557684D01*
G01X40354Y1562721D02*
X4467D01*
G01D02*
Y1627287D01*
X40354D01*
G01X12028Y1640098D02*
X8928D01*
Y1641057D01*
X9083Y1641363D01*
X9290Y1641555D01*
X9703Y1641632D01*
X10116Y1641555D01*
X10375Y1641325D01*
X10530Y1641057D01*
Y1640098D01*
G01Y1641057D02*
X12028Y1641632D01*
G01Y1643965D02*
X8928D01*
X9548Y1643505D01*
G01X12028D02*
Y1644425D01*
G01X11563Y1646222D02*
X11821Y1646452D01*
X11976Y1646720D01*
X12028Y1647065D01*
X11925Y1647410D01*
X11718Y1647678D01*
X11356Y1647870D01*
X10943Y1647908D01*
X10530Y1647832D01*
X10271Y1647640D01*
X10065Y1647372D01*
X10013Y1647103D01*
X10065Y1646835D01*
X10271Y1646490D01*
X8928Y1646605D01*
Y1647640D01*
G01X12028Y1650165D02*
X8928D01*
X9548Y1649705D01*
G01X12028D02*
Y1650625D01*
G01X12753Y1636960D02*
Y1630760D01*
X9553D01*
Y1636960D01*
X12753D01*
G01X17287Y1640097D02*
X14187D01*
Y1641056D01*
X14342Y1641362D01*
X14549Y1641554D01*
X14962Y1641631D01*
X15375Y1641554D01*
X15634Y1641324D01*
X15789Y1641056D01*
Y1640097D01*
G01Y1641056D02*
X17287Y1641631D01*
G01Y1643964D02*
X14187D01*
X14807Y1643504D01*
G01X17287D02*
Y1644424D01*
G01X16822Y1646221D02*
X17080Y1646451D01*
X17235Y1646719D01*
X17287Y1647064D01*
X17184Y1647409D01*
X16977Y1647677D01*
X16615Y1647869D01*
X16202Y1647907D01*
X15789Y1647831D01*
X15530Y1647639D01*
X15324Y1647371D01*
X15272Y1647102D01*
X15324Y1646834D01*
X15530Y1646489D01*
X14187Y1646604D01*
Y1647639D01*
G01X14704Y1649436D02*
X14394Y1649666D01*
X14239Y1649934D01*
X14187Y1650241D01*
X14290Y1650624D01*
X14549Y1650892D01*
X14859Y1650969D01*
X15169Y1650931D01*
X15427Y1650777D01*
X15944Y1650011D01*
X16305Y1649666D01*
X16822Y1649436D01*
X17287Y1649359D01*
Y1650969D01*
G01X18152Y1636828D02*
Y1630628D01*
X14952D01*
Y1636828D01*
X18152D01*
G01X20909Y1652987D02*
X21139Y1653297D01*
X21407Y1653452D01*
X21714Y1653504D01*
X22097Y1653401D01*
X22365Y1653142D01*
X22442Y1652832D01*
X22404Y1652522D01*
X22250Y1652264D01*
X21484Y1651747D01*
X21139Y1651386D01*
X20909Y1650869D01*
X20832Y1650404D01*
X22442D01*
G01X24737Y1653504D02*
X24430Y1653401D01*
X24200Y1653142D01*
X24047Y1652832D01*
X23932Y1652419D01*
X23894Y1651954D01*
X23932Y1651489D01*
X24047Y1651076D01*
X24200Y1650766D01*
X24430Y1650507D01*
X24737Y1650404D01*
X25044Y1650507D01*
X25274Y1650766D01*
X25427Y1651076D01*
X25542Y1651489D01*
X25580Y1651954D01*
X25542Y1652419D01*
X25427Y1652832D01*
X25274Y1653142D01*
X25044Y1653401D01*
X24737Y1653504D01*
G01X54702Y1657457D02*
Y1655882D01*
X16119D01*
Y1657457D01*
G01Y1829110D02*
X54702D01*
Y1657457D01*
X16119D01*
Y1830685D01*
X54702D01*
Y1829110D01*
G01X16119Y1750370D02*
X9820D01*
Y1736197D01*
X16119D01*
G01X9992Y1817623D02*
Y1820723D01*
X9532Y1820103D01*
G01Y1817623D02*
X10452D01*
G01X13092D02*
Y1820723D01*
X12632Y1820103D01*
G01Y1817623D02*
X13552D01*
G01X23698Y1834558D02*
X23890Y1834248D01*
X24120Y1834041D01*
X24388Y1833938D01*
X24695Y1834041D01*
X24925Y1834248D01*
X25155Y1834558D01*
X25232Y1834971D01*
Y1837038D01*
G01X26837Y1836521D02*
X27067Y1836831D01*
X27335Y1836986D01*
X27642Y1837038D01*
X28025Y1836935D01*
X28293Y1836676D01*
X28370Y1836366D01*
X28332Y1836056D01*
X28178Y1835798D01*
X27412Y1835281D01*
X27067Y1834920D01*
X26837Y1834403D01*
X26760Y1833938D01*
X28370D01*
G01X30665Y1837038D02*
X30358Y1836935D01*
X30128Y1836676D01*
X29975Y1836366D01*
X29860Y1835953D01*
X29822Y1835488D01*
X29860Y1835023D01*
X29975Y1834610D01*
X30128Y1834300D01*
X30358Y1834041D01*
X30665Y1833938D01*
X30972Y1834041D01*
X31202Y1834300D01*
X31355Y1834610D01*
X31470Y1835023D01*
X31508Y1835488D01*
X31470Y1835953D01*
X31355Y1836366D01*
X31202Y1836676D01*
X30972Y1836935D01*
X30665Y1837038D01*
G01X26756Y1891721D02*
X15276D01*
Y1877843D01*
X10551D01*
Y1867606D01*
X15276D01*
Y1853728D01*
X26756D01*
G01X15539Y1893517D02*
X15731Y1893207D01*
X15961Y1893000D01*
X16229Y1892897D01*
X16536Y1893000D01*
X16766Y1893207D01*
X16996Y1893517D01*
X17073Y1893930D01*
Y1895997D01*
G01X18563Y1893517D02*
X18793Y1893155D01*
X19099Y1892949D01*
X19444Y1892897D01*
X19751Y1892949D01*
X20058Y1893207D01*
X20249Y1893517D01*
X20288Y1893827D01*
X20211Y1894189D01*
X19943Y1894447D01*
X19674Y1894550D01*
X19329D01*
G01X19674D02*
X19904Y1894705D01*
X20096Y1894964D01*
X20173Y1895274D01*
X20096Y1895584D01*
X19904Y1895842D01*
X19559Y1895997D01*
X19214Y1895945D01*
X18869Y1895739D01*
G01X22506Y1895997D02*
X22199Y1895894D01*
X21969Y1895635D01*
X21816Y1895325D01*
X21701Y1894912D01*
X21663Y1894447D01*
X21701Y1893982D01*
X21816Y1893569D01*
X21969Y1893259D01*
X22199Y1893000D01*
X22506Y1892897D01*
X22813Y1893000D01*
X23043Y1893259D01*
X23196Y1893569D01*
X23311Y1893982D01*
X23349Y1894447D01*
X23311Y1894912D01*
X23196Y1895325D01*
X23043Y1895635D01*
X22813Y1895894D01*
X22506Y1895997D01*
G01X26756Y1973720D02*
X15276D01*
Y1959842D01*
X10551D01*
Y1949605D01*
X15276D01*
Y1935727D01*
X26756D01*
G01X15539Y1975516D02*
X15731Y1975206D01*
X15961Y1974999D01*
X16229Y1974896D01*
X16536Y1974999D01*
X16766Y1975206D01*
X16996Y1975516D01*
X17073Y1975929D01*
Y1977996D01*
G01X18563Y1975516D02*
X18793Y1975154D01*
X19099Y1974948D01*
X19444Y1974896D01*
X19751Y1974948D01*
X20058Y1975206D01*
X20249Y1975516D01*
X20288Y1975826D01*
X20211Y1976188D01*
X19943Y1976446D01*
X19674Y1976549D01*
X19329D01*
G01X19674D02*
X19904Y1976704D01*
X20096Y1976963D01*
X20173Y1977273D01*
X20096Y1977583D01*
X19904Y1977841D01*
X19559Y1977996D01*
X19214Y1977944D01*
X18869Y1977738D01*
G01X22506Y1974896D02*
Y1977996D01*
X22046Y1977376D01*
G01Y1974896D02*
X22966D01*
G01X26756Y2048720D02*
X15276D01*
Y2034842D01*
X10551D01*
Y2024605D01*
X15276D01*
Y2010727D01*
X26756D01*
G01X15539Y2050516D02*
X15731Y2050206D01*
X15961Y2049999D01*
X16229Y2049896D01*
X16536Y2049999D01*
X16766Y2050206D01*
X16996Y2050516D01*
X17073Y2050929D01*
Y2052996D01*
G01X18563Y2050516D02*
X18793Y2050154D01*
X19099Y2049948D01*
X19444Y2049896D01*
X19751Y2049948D01*
X20058Y2050206D01*
X20249Y2050516D01*
X20288Y2050826D01*
X20211Y2051188D01*
X19943Y2051446D01*
X19674Y2051549D01*
X19329D01*
G01X19674D02*
X19904Y2051704D01*
X20096Y2051963D01*
X20173Y2052273D01*
X20096Y2052583D01*
X19904Y2052841D01*
X19559Y2052996D01*
X19214Y2052944D01*
X18869Y2052738D01*
G01X21778Y2052479D02*
X22008Y2052789D01*
X22276Y2052944D01*
X22583Y2052996D01*
X22966Y2052893D01*
X23234Y2052634D01*
X23311Y2052324D01*
X23273Y2052014D01*
X23119Y2051756D01*
X22353Y2051239D01*
X22008Y2050878D01*
X21778Y2050361D01*
X21701Y2049896D01*
X23311D01*
G01X96850Y114960D02*
G03I-31496J0D01*
G01X27258Y87443D02*
X27450Y87133D01*
X27680Y86926D01*
X27948Y86823D01*
X28255Y86926D01*
X28485Y87133D01*
X28715Y87443D01*
X28792Y87856D01*
Y89923D01*
G01X31125Y86823D02*
Y89923D01*
X30665Y89303D01*
G01Y86823D02*
X31585D01*
G01X33573Y87185D02*
X33842Y86926D01*
X34148Y86823D01*
X34455Y86926D01*
X34723Y87236D01*
X34915Y87701D01*
X34992Y88166D01*
Y88735D01*
X34915Y89200D01*
X34723Y89613D01*
X34493Y89820D01*
X34225Y89923D01*
X33918Y89820D01*
X33688Y89613D01*
X33535Y89303D01*
X33458Y88890D01*
X33535Y88528D01*
X33727Y88166D01*
X33957Y87960D01*
X34225Y87908D01*
X34532Y88011D01*
X34762Y88270D01*
X34992Y88735D01*
G01X47510Y84790D02*
Y87890D01*
X47050Y87270D01*
G01Y84790D02*
X47970D01*
G01X32480Y105418D02*
Y134018D01*
G01X93980Y156008D02*
X76026D01*
X68725Y148707D01*
X50567D01*
X41294Y139434D01*
X40604Y140124D01*
Y143381D01*
G01X41294Y139434D02*
X43859D01*
X43958Y139533D01*
G01X34270Y223132D02*
X34462Y222822D01*
X34692Y222615D01*
X34960Y222512D01*
X35267Y222615D01*
X35497Y222822D01*
X35727Y223132D01*
X35804Y223545D01*
Y225612D01*
G01X37409Y225095D02*
X37639Y225405D01*
X37907Y225560D01*
X38214Y225612D01*
X38597Y225509D01*
X38865Y225250D01*
X38942Y224940D01*
X38904Y224630D01*
X38750Y224372D01*
X37984Y223855D01*
X37639Y223494D01*
X37409Y222977D01*
X37332Y222512D01*
X38942D01*
G01X41237D02*
Y225612D01*
X40777Y224992D01*
G01Y222512D02*
X41697D01*
G01X32677Y296235D02*
X32869Y295925D01*
X33099Y295718D01*
X33367Y295615D01*
X33674Y295718D01*
X33904Y295925D01*
X34134Y296235D01*
X34211Y296648D01*
Y298715D01*
G01X35816Y298198D02*
X36046Y298508D01*
X36314Y298663D01*
X36621Y298715D01*
X37004Y298612D01*
X37272Y298353D01*
X37349Y298043D01*
X37311Y297733D01*
X37157Y297475D01*
X36391Y296958D01*
X36046Y296597D01*
X35816Y296080D01*
X35739Y295615D01*
X37349D01*
G01X38801Y296235D02*
X39031Y295873D01*
X39337Y295667D01*
X39682Y295615D01*
X39989Y295667D01*
X40296Y295925D01*
X40487Y296235D01*
X40526Y296545D01*
X40449Y296907D01*
X40181Y297165D01*
X39912Y297268D01*
X39567D01*
G01X39912D02*
X40142Y297423D01*
X40334Y297682D01*
X40411Y297992D01*
X40334Y298302D01*
X40142Y298560D01*
X39797Y298715D01*
X39452Y298663D01*
X39107Y298457D01*
G01X32204Y308438D02*
Y348838D01*
G01X96850Y464960D02*
G03I-31496J0D01*
G01X38015Y430930D02*
X38207Y430620D01*
X38437Y430413D01*
X38705Y430310D01*
X39012Y430413D01*
X39242Y430620D01*
X39472Y430930D01*
X39549Y431343D01*
Y433410D01*
G01X41154Y432893D02*
X41384Y433203D01*
X41652Y433358D01*
X41959Y433410D01*
X42342Y433307D01*
X42610Y433048D01*
X42687Y432738D01*
X42649Y432428D01*
X42495Y432170D01*
X41729Y431653D01*
X41384Y431292D01*
X41154Y430775D01*
X41077Y430310D01*
X42687D01*
G01X44905D02*
X44982Y430982D01*
X45097Y431550D01*
X45250Y432067D01*
X45442Y432635D01*
X45749Y433410D01*
X44215D01*
G01X34643Y487688D02*
Y490788D01*
G01X36253D02*
Y487688D01*
G01Y489238D02*
X34643D01*
G01X38548Y487688D02*
Y490788D01*
X38088Y490168D01*
G01Y487688D02*
X39008D01*
G01X41648Y490788D02*
X41341Y490685D01*
X41111Y490426D01*
X40958Y490116D01*
X40843Y489703D01*
X40805Y489238D01*
X40843Y488773D01*
X40958Y488360D01*
X41111Y488050D01*
X41341Y487791D01*
X41648Y487688D01*
X41955Y487791D01*
X42185Y488050D01*
X42338Y488360D01*
X42453Y488773D01*
X42491Y489238D01*
X42453Y489703D01*
X42338Y490116D01*
X42185Y490426D01*
X41955Y490685D01*
X41648Y490788D01*
G01X31730Y575540D02*
X31922Y575230D01*
X32152Y575023D01*
X32420Y574920D01*
X32727Y575023D01*
X32957Y575230D01*
X33187Y575540D01*
X33264Y575953D01*
Y578020D01*
G01X34869Y577503D02*
X35099Y577813D01*
X35367Y577968D01*
X35674Y578020D01*
X36057Y577917D01*
X36325Y577658D01*
X36402Y577348D01*
X36364Y577038D01*
X36210Y576780D01*
X35444Y576263D01*
X35099Y575902D01*
X34869Y575385D01*
X34792Y574920D01*
X36402D01*
G01X38045Y575282D02*
X38314Y575023D01*
X38620Y574920D01*
X38927Y575023D01*
X39195Y575333D01*
X39387Y575798D01*
X39464Y576263D01*
Y576832D01*
X39387Y577297D01*
X39195Y577710D01*
X38965Y577917D01*
X38697Y578020D01*
X38390Y577917D01*
X38160Y577710D01*
X38007Y577400D01*
X37930Y576987D01*
X38007Y576625D01*
X38199Y576263D01*
X38429Y576057D01*
X38697Y576005D01*
X39004Y576108D01*
X39234Y576367D01*
X39464Y576832D01*
G01X34630Y681224D02*
X31530Y682182D01*
X34630Y683140D01*
G01X33545Y682795D02*
Y681569D01*
G01X34630Y685282D02*
X34578Y685550D01*
X34423Y685857D01*
X34165Y686049D01*
X33803Y686125D01*
X33442Y686049D01*
X33132Y685819D01*
X32977Y685474D01*
Y685090D01*
X32873Y684860D01*
X32615Y684669D01*
X32253Y684592D01*
X31892Y684707D01*
X31633Y684975D01*
X31530Y685282D01*
X31633Y685589D01*
X31892Y685857D01*
X32253Y685972D01*
X32615Y685895D01*
X32873Y685704D01*
X32977Y685474D01*
Y685090D01*
X33132Y684745D01*
X33442Y684515D01*
X33803Y684439D01*
X34165Y684515D01*
X34423Y684707D01*
X34578Y685014D01*
X34630Y685282D01*
G01X32047Y687654D02*
X31737Y687884D01*
X31582Y688152D01*
X31530Y688459D01*
X31633Y688842D01*
X31892Y689110D01*
X32202Y689187D01*
X32512Y689149D01*
X32770Y688995D01*
X33287Y688229D01*
X33648Y687884D01*
X34165Y687654D01*
X34630Y687577D01*
Y689187D01*
G01X96850Y814960D02*
G03I-31496J0D01*
G01X33053Y1034796D02*
X29953Y1035754D01*
X33053Y1036712D01*
G01X31968Y1036367D02*
Y1035141D01*
G01X30470Y1038126D02*
X30160Y1038356D01*
X30005Y1038624D01*
X29953Y1038931D01*
X30056Y1039314D01*
X30315Y1039582D01*
X30625Y1039659D01*
X30935Y1039621D01*
X31193Y1039467D01*
X31710Y1038701D01*
X32071Y1038356D01*
X32588Y1038126D01*
X33053Y1038049D01*
Y1039659D01*
G01X34390Y1051200D02*
X31290Y1052158D01*
X34390Y1053116D01*
G01X33305Y1052771D02*
Y1051545D01*
G01X34390Y1055258D02*
X34338Y1055526D01*
X34183Y1055833D01*
X33925Y1056025D01*
X33563Y1056101D01*
X33202Y1056025D01*
X32892Y1055795D01*
X32737Y1055450D01*
Y1055066D01*
X32633Y1054836D01*
X32375Y1054645D01*
X32013Y1054568D01*
X31652Y1054683D01*
X31393Y1054951D01*
X31290Y1055258D01*
X31393Y1055565D01*
X31652Y1055833D01*
X32013Y1055948D01*
X32375Y1055871D01*
X32633Y1055680D01*
X32737Y1055450D01*
Y1055066D01*
X32892Y1054721D01*
X33202Y1054491D01*
X33563Y1054415D01*
X33925Y1054491D01*
X34183Y1054683D01*
X34338Y1054990D01*
X34390Y1055258D01*
G01Y1058358D02*
X31290D01*
X31910Y1057898D01*
G01X34390D02*
Y1058818D01*
G01X96850Y1164960D02*
G03I-31496J0D01*
G01X51931Y1304205D02*
Y1298005D01*
X48731D01*
Y1304205D01*
X51931D01*
G01X34308Y1403060D02*
X31208Y1404018D01*
X34308Y1404976D01*
G01X33223Y1404631D02*
Y1403405D01*
G01X31725Y1406390D02*
X31415Y1406620D01*
X31260Y1406888D01*
X31208Y1407195D01*
X31311Y1407578D01*
X31570Y1407846D01*
X31880Y1407923D01*
X32190Y1407885D01*
X32448Y1407731D01*
X32965Y1406965D01*
X33326Y1406620D01*
X33843Y1406390D01*
X34308Y1406313D01*
Y1407923D01*
G01X96850Y1514960D02*
G03I-31496J0D01*
G01X40299Y1541627D02*
Y1544727D01*
G01X41909D02*
Y1541627D01*
G01Y1543177D02*
X40299D01*
G01X43476Y1542919D02*
X43744Y1543280D01*
X43974Y1543487D01*
X44281Y1543590D01*
X44549Y1543487D01*
X44741Y1543280D01*
X44894Y1542970D01*
X44932Y1542609D01*
X44894Y1542299D01*
X44741Y1541989D01*
X44511Y1541730D01*
X44242Y1541627D01*
X43936Y1541730D01*
X43667Y1542040D01*
X43514Y1542505D01*
X43476Y1543022D01*
X43552Y1543694D01*
X43667Y1544055D01*
X43859Y1544417D01*
X44127Y1544675D01*
X44396Y1544727D01*
X44664Y1544624D01*
X44856Y1544365D01*
G01X44793Y1649615D02*
Y1652715D01*
X44333Y1652095D01*
G01Y1649615D02*
X45253D01*
G01X47893Y1652715D02*
X47586Y1652612D01*
X47356Y1652353D01*
X47203Y1652043D01*
X47088Y1651630D01*
X47050Y1651165D01*
X47088Y1650700D01*
X47203Y1650287D01*
X47356Y1649977D01*
X47586Y1649718D01*
X47893Y1649615D01*
X48200Y1649718D01*
X48430Y1649977D01*
X48583Y1650287D01*
X48698Y1650700D01*
X48736Y1651165D01*
X48698Y1651630D01*
X48583Y1652043D01*
X48430Y1652353D01*
X48200Y1652612D01*
X47893Y1652715D01*
G01X96850Y1864960D02*
G03I-31496J0D01*
G01X39601Y1833141D02*
Y1836241D01*
X39141Y1835621D01*
G01Y1833141D02*
X40061D01*
G01X32480Y1858419D02*
Y1887019D01*
G01X40299Y1891627D02*
Y1894727D01*
G01X41909D02*
Y1891627D01*
G01Y1893177D02*
X40299D01*
G01X44204Y1891627D02*
X44472Y1891679D01*
X44779Y1891834D01*
X44971Y1892092D01*
X45047Y1892454D01*
X44971Y1892815D01*
X44741Y1893125D01*
X44396Y1893280D01*
X44012D01*
X43782Y1893384D01*
X43591Y1893642D01*
X43514Y1894004D01*
X43629Y1894365D01*
X43897Y1894624D01*
X44204Y1894727D01*
X44511Y1894624D01*
X44779Y1894365D01*
X44894Y1894004D01*
X44817Y1893642D01*
X44626Y1893384D01*
X44396Y1893280D01*
X44012D01*
X43667Y1893125D01*
X43437Y1892815D01*
X43361Y1892454D01*
X43437Y1892092D01*
X43629Y1891834D01*
X43936Y1891679D01*
X44204Y1891627D01*
G01X32480Y1940418D02*
Y1969018D01*
G01Y2015418D02*
Y2044018D01*
G01X64500Y18120D02*
X64768Y18172D01*
X65075Y18327D01*
X65267Y18585D01*
X65343Y18947D01*
X65267Y19308D01*
X65037Y19618D01*
X64692Y19773D01*
X64308D01*
X64078Y19877D01*
X63887Y20135D01*
X63810Y20497D01*
X63925Y20858D01*
X64193Y21117D01*
X64500Y21220D01*
X64807Y21117D01*
X65075Y20858D01*
X65190Y20497D01*
X65113Y20135D01*
X64922Y19877D01*
X64692Y19773D01*
X64308D01*
X63963Y19618D01*
X63733Y19308D01*
X63657Y18947D01*
X63733Y18585D01*
X63925Y18327D01*
X64232Y18172D01*
X64500Y18120D01*
G01X53568Y17999D02*
X53645Y18671D01*
X53760Y19239D01*
X53913Y19756D01*
X54105Y20324D01*
X54412Y21099D01*
X52878D01*
G01X72459Y82433D02*
X72689Y82743D01*
X72957Y82898D01*
X73264Y82950D01*
X73647Y82847D01*
X73915Y82588D01*
X73992Y82278D01*
X73954Y81968D01*
X73800Y81710D01*
X73034Y81193D01*
X72689Y80832D01*
X72459Y80315D01*
X72382Y79850D01*
X73992D01*
G01X54687Y153570D02*
X54764Y154242D01*
X54879Y154810D01*
X55032Y155327D01*
X55224Y155895D01*
X55531Y156670D01*
X53997D01*
G01X71012Y163235D02*
Y360085D01*
X94634D01*
Y163235D01*
X71012D01*
G01X65250Y154260D02*
X65518Y154312D01*
X65825Y154467D01*
X66017Y154725D01*
X66093Y155087D01*
X66017Y155448D01*
X65787Y155758D01*
X65442Y155913D01*
X65058D01*
X64828Y156017D01*
X64637Y156275D01*
X64560Y156637D01*
X64675Y156998D01*
X64943Y157257D01*
X65250Y157360D01*
X65557Y157257D01*
X65825Y156998D01*
X65940Y156637D01*
X65863Y156275D01*
X65672Y156017D01*
X65442Y155913D01*
X65058D01*
X64713Y155758D01*
X64483Y155448D01*
X64407Y155087D01*
X64483Y154725D01*
X64675Y154467D01*
X64982Y154312D01*
X65250Y154260D01*
G01X65524Y223836D02*
X65754Y224146D01*
X66022Y224301D01*
X66329Y224353D01*
X66712Y224250D01*
X66980Y223991D01*
X67057Y223681D01*
X67019Y223371D01*
X66865Y223113D01*
X66099Y222596D01*
X65754Y222235D01*
X65524Y221718D01*
X65447Y221253D01*
X67057D01*
G01X59363Y221114D02*
Y224214D01*
X58903Y223594D01*
G01Y221114D02*
X59823D01*
G01X65596Y227311D02*
X65864Y227363D01*
X66171Y227518D01*
X66363Y227776D01*
X66439Y228138D01*
X66363Y228499D01*
X66133Y228809D01*
X65788Y228964D01*
X65404D01*
X65174Y229068D01*
X64983Y229326D01*
X64906Y229688D01*
X65021Y230049D01*
X65289Y230308D01*
X65596Y230411D01*
X65903Y230308D01*
X66171Y230049D01*
X66286Y229688D01*
X66209Y229326D01*
X66018Y229068D01*
X65788Y228964D01*
X65404D01*
X65059Y228809D01*
X64829Y228499D01*
X64753Y228138D01*
X64829Y227776D01*
X65021Y227518D01*
X65328Y227363D01*
X65596Y227311D01*
G01X55181Y227190D02*
X55258Y227862D01*
X55373Y228430D01*
X55526Y228947D01*
X55718Y229515D01*
X56025Y230290D01*
X54491D01*
G01X64270Y296744D02*
X64500Y297054D01*
X64768Y297209D01*
X65075Y297261D01*
X65458Y297158D01*
X65726Y296899D01*
X65803Y296589D01*
X65765Y296279D01*
X65611Y296021D01*
X64845Y295504D01*
X64500Y295143D01*
X64270Y294626D01*
X64193Y294161D01*
X65803D01*
G01X52034Y294880D02*
Y297980D01*
X51574Y297360D01*
G01Y294880D02*
X52494D01*
G01X65229Y362796D02*
X65497Y362848D01*
X65804Y363003D01*
X65996Y363261D01*
X66072Y363623D01*
X65996Y363984D01*
X65766Y364294D01*
X65421Y364449D01*
X65037D01*
X64807Y364553D01*
X64616Y364811D01*
X64539Y365173D01*
X64654Y365534D01*
X64922Y365793D01*
X65229Y365896D01*
X65536Y365793D01*
X65804Y365534D01*
X65919Y365173D01*
X65842Y364811D01*
X65651Y364553D01*
X65421Y364449D01*
X65037D01*
X64692Y364294D01*
X64462Y363984D01*
X64386Y363623D01*
X64462Y363261D01*
X64654Y363003D01*
X64961Y362848D01*
X65229Y362796D01*
G01X55553Y362549D02*
X55630Y363221D01*
X55745Y363789D01*
X55898Y364306D01*
X56090Y364874D01*
X56397Y365649D01*
X54863D01*
G01X63953Y432520D02*
X64183Y432830D01*
X64451Y432985D01*
X64758Y433037D01*
X65141Y432934D01*
X65409Y432675D01*
X65486Y432365D01*
X65448Y432055D01*
X65294Y431797D01*
X64528Y431280D01*
X64183Y430919D01*
X63953Y430402D01*
X63876Y429937D01*
X65486D01*
G01X54026Y430609D02*
Y433709D01*
X53566Y433089D01*
G01Y430609D02*
X54486D01*
G01X66764Y500117D02*
X67032Y500169D01*
X67339Y500324D01*
X67531Y500582D01*
X67607Y500944D01*
X67531Y501305D01*
X67301Y501615D01*
X66956Y501770D01*
X66572D01*
X66342Y501874D01*
X66151Y502132D01*
X66074Y502494D01*
X66189Y502855D01*
X66457Y503114D01*
X66764Y503217D01*
X67071Y503114D01*
X67339Y502855D01*
X67454Y502494D01*
X67377Y502132D01*
X67186Y501874D01*
X66956Y501770D01*
X66572D01*
X66227Y501615D01*
X65997Y501305D01*
X65921Y500944D01*
X65997Y500582D01*
X66189Y500324D01*
X66496Y500169D01*
X66764Y500117D01*
G01X54625Y499813D02*
X54702Y500485D01*
X54817Y501053D01*
X54970Y501570D01*
X55162Y502138D01*
X55469Y502913D01*
X53935D01*
G01X50454Y569283D02*
X70215D01*
Y504717D01*
X50454D01*
G01X65843Y586621D02*
X60843D01*
Y588141D01*
X61093Y588648D01*
X61676Y589028D01*
X62343Y589155D01*
X63010Y589028D01*
X63510Y588711D01*
X63760Y588141D01*
Y586621D01*
G01X66010Y591848D02*
X60843Y594128D01*
G01X65843Y596631D02*
X60843D01*
X65843Y599545D01*
X60843D01*
G01X66010Y603188D02*
X65926Y603061D01*
X65760D01*
X65676Y603188D01*
X65760Y603315D01*
X65926D01*
X66010Y603188D01*
G01X63760D02*
X63676Y603061D01*
X63510D01*
X63426Y603188D01*
X63510Y603315D01*
X63676D01*
X63760Y603188D01*
G01X65843Y606895D02*
X60843D01*
Y608161D01*
X61093Y608668D01*
X61426Y609048D01*
X61926Y609365D01*
X62510Y609618D01*
X63343Y609681D01*
X64176Y609618D01*
X64760Y609365D01*
X65260Y609048D01*
X65593Y608668D01*
X65843Y608161D01*
Y606895D01*
G01Y611805D02*
X60843Y613388D01*
X65843Y614971D01*
G01X64093Y614401D02*
Y612375D01*
G01X60843Y618488D02*
X65843D01*
G01X60843Y617031D02*
Y619945D01*
G01X63760Y622385D02*
X63176Y622828D01*
X62843Y623208D01*
X62676Y623715D01*
X62843Y624158D01*
X63176Y624475D01*
X63676Y624728D01*
X64260Y624791D01*
X64760Y624728D01*
X65260Y624475D01*
X65676Y624095D01*
X65843Y623651D01*
X65676Y623145D01*
X65176Y622701D01*
X64426Y622448D01*
X63593Y622385D01*
X62510Y622511D01*
X61926Y622701D01*
X61343Y623018D01*
X60926Y623461D01*
X60843Y623905D01*
X61010Y624348D01*
X61426Y624665D01*
G01X65843Y627041D02*
X60843D01*
X65010Y628688D01*
X60843Y630335D01*
X65843D01*
G01X60843Y633788D02*
X65843D01*
G01X60843Y632331D02*
Y635245D01*
G01X63176Y639395D02*
X62926Y639648D01*
X62510Y639838D01*
X61926Y639965D01*
X61426Y639838D01*
X61093Y639585D01*
X60843Y639141D01*
Y637431D01*
X65843D01*
Y639521D01*
X65510Y639965D01*
X65010Y640218D01*
X64426Y640345D01*
X63843Y640218D01*
X63343Y639838D01*
X63176Y639395D01*
Y637431D01*
G01X65843Y643988D02*
X65760Y644431D01*
X65510Y644938D01*
X65093Y645255D01*
X64510Y645381D01*
X63926Y645255D01*
X63426Y644875D01*
X63176Y644305D01*
Y643671D01*
X63010Y643291D01*
X62593Y642975D01*
X62010Y642848D01*
X61426Y643038D01*
X61010Y643481D01*
X60843Y643988D01*
X61010Y644495D01*
X61426Y644938D01*
X62010Y645128D01*
X62593Y645001D01*
X63010Y644685D01*
X63176Y644305D01*
Y643671D01*
X63426Y643101D01*
X63926Y642721D01*
X64510Y642595D01*
X65093Y642721D01*
X65510Y643038D01*
X65760Y643545D01*
X65843Y643988D01*
G01Y649088D02*
X65760Y649531D01*
X65510Y650038D01*
X65093Y650355D01*
X64510Y650481D01*
X63926Y650355D01*
X63426Y649975D01*
X63176Y649405D01*
Y648771D01*
X63010Y648391D01*
X62593Y648075D01*
X62010Y647948D01*
X61426Y648138D01*
X61010Y648581D01*
X60843Y649088D01*
X61010Y649595D01*
X61426Y650038D01*
X62010Y650228D01*
X62593Y650101D01*
X63010Y649785D01*
X63176Y649405D01*
Y648771D01*
X63426Y648201D01*
X63926Y647821D01*
X64510Y647695D01*
X65093Y647821D01*
X65510Y648138D01*
X65760Y648645D01*
X65843Y649088D01*
G01Y652605D02*
X60843Y654188D01*
X65843Y655771D01*
G01X64093Y655201D02*
Y653175D01*
G01X60843Y659288D02*
X61010Y658781D01*
X61426Y658401D01*
X61926Y658148D01*
X62593Y657958D01*
X63343Y657895D01*
X64093Y657958D01*
X64760Y658148D01*
X65260Y658401D01*
X65676Y658781D01*
X65843Y659288D01*
X65676Y659795D01*
X65260Y660175D01*
X64760Y660428D01*
X64093Y660618D01*
X63343Y660681D01*
X62593Y660618D01*
X61926Y660428D01*
X61426Y660175D01*
X61010Y659795D01*
X60843Y659288D01*
G01X66381Y573640D02*
X66611Y573950D01*
X66879Y574105D01*
X67186Y574157D01*
X67569Y574054D01*
X67837Y573795D01*
X67914Y573485D01*
X67876Y573175D01*
X67722Y572917D01*
X66956Y572400D01*
X66611Y572039D01*
X66381Y571522D01*
X66304Y571057D01*
X67914D01*
G01X58520Y570806D02*
Y573906D01*
X58060Y573286D01*
G01Y570806D02*
X58980D01*
G01X72507Y696177D02*
X69407D01*
Y697136D01*
X69562Y697442D01*
X69769Y697634D01*
X70182Y697711D01*
X70595Y697634D01*
X70854Y697404D01*
X71009Y697136D01*
Y696177D01*
G01Y697136D02*
X72507Y697711D01*
G01Y700044D02*
X69407D01*
X70027Y699584D01*
G01X72507D02*
Y700504D01*
G01X71215Y702416D02*
X70854Y702684D01*
X70647Y702914D01*
X70544Y703221D01*
X70647Y703489D01*
X70854Y703681D01*
X71164Y703834D01*
X71525Y703872D01*
X71835Y703834D01*
X72145Y703681D01*
X72404Y703451D01*
X72507Y703182D01*
X72404Y702876D01*
X72094Y702607D01*
X71629Y702454D01*
X71112Y702416D01*
X70440Y702492D01*
X70079Y702607D01*
X69717Y702799D01*
X69459Y703067D01*
X69407Y703336D01*
X69510Y703604D01*
X69769Y703796D01*
G01X69407Y706244D02*
X69510Y705937D01*
X69769Y705707D01*
X70079Y705554D01*
X70492Y705439D01*
X70957Y705401D01*
X71422Y705439D01*
X71835Y705554D01*
X72145Y705707D01*
X72404Y705937D01*
X72507Y706244D01*
X72404Y706551D01*
X72145Y706781D01*
X71835Y706934D01*
X71422Y707049D01*
X70957Y707087D01*
X70492Y707049D01*
X70079Y706934D01*
X69769Y706781D01*
X69510Y706551D01*
X69407Y706244D01*
G01X64157Y696250D02*
X61057D01*
Y697209D01*
X61212Y697515D01*
X61419Y697707D01*
X61832Y697784D01*
X62245Y697707D01*
X62504Y697477D01*
X62659Y697209D01*
Y696250D01*
G01Y697209D02*
X64157Y697784D01*
G01Y700117D02*
X61057D01*
X61677Y699657D01*
G01X64157D02*
Y700577D01*
G01X63692Y702374D02*
X63950Y702604D01*
X64105Y702872D01*
X64157Y703217D01*
X64054Y703562D01*
X63847Y703830D01*
X63485Y704022D01*
X63072Y704060D01*
X62659Y703984D01*
X62400Y703792D01*
X62194Y703524D01*
X62142Y703255D01*
X62194Y702987D01*
X62400Y702642D01*
X61057Y702757D01*
Y703792D01*
G01X64157Y706317D02*
X64105Y706585D01*
X63950Y706892D01*
X63692Y707084D01*
X63330Y707160D01*
X62969Y707084D01*
X62659Y706854D01*
X62504Y706509D01*
Y706125D01*
X62400Y705895D01*
X62142Y705704D01*
X61780Y705627D01*
X61419Y705742D01*
X61160Y706010D01*
X61057Y706317D01*
X61160Y706624D01*
X61419Y706892D01*
X61780Y707007D01*
X62142Y706930D01*
X62400Y706739D01*
X62504Y706509D01*
Y706125D01*
X62659Y705780D01*
X62969Y705550D01*
X63330Y705474D01*
X63692Y705550D01*
X63950Y705742D01*
X64105Y706049D01*
X64157Y706317D01*
G01X68287Y696200D02*
X65187D01*
Y697159D01*
X65342Y697465D01*
X65549Y697657D01*
X65962Y697734D01*
X66375Y697657D01*
X66634Y697427D01*
X66789Y697159D01*
Y696200D01*
G01Y697159D02*
X68287Y697734D01*
G01Y700067D02*
X65187D01*
X65807Y699607D01*
G01X68287D02*
Y700527D01*
G01X67822Y702324D02*
X68080Y702554D01*
X68235Y702822D01*
X68287Y703167D01*
X68184Y703512D01*
X67977Y703780D01*
X67615Y703972D01*
X67202Y704010D01*
X66789Y703934D01*
X66530Y703742D01*
X66324Y703474D01*
X66272Y703205D01*
X66324Y702937D01*
X66530Y702592D01*
X65187Y702707D01*
Y703742D01*
G01X67925Y705615D02*
X68184Y705884D01*
X68287Y706190D01*
X68184Y706497D01*
X67874Y706765D01*
X67409Y706957D01*
X66944Y707034D01*
X66375D01*
X65910Y706957D01*
X65497Y706765D01*
X65290Y706535D01*
X65187Y706267D01*
X65290Y705960D01*
X65497Y705730D01*
X65807Y705577D01*
X66220Y705500D01*
X66582Y705577D01*
X66944Y705769D01*
X67150Y705999D01*
X67202Y706267D01*
X67099Y706574D01*
X66840Y706804D01*
X66375Y707034D01*
G01X53735Y849002D02*
Y852102D01*
G01X55345D02*
Y849002D01*
G01Y850552D02*
X53735D01*
G01X56912Y851585D02*
X57142Y851895D01*
X57410Y852050D01*
X57717Y852102D01*
X58100Y851999D01*
X58368Y851740D01*
X58445Y851430D01*
X58407Y851120D01*
X58253Y850862D01*
X57487Y850345D01*
X57142Y849984D01*
X56912Y849467D01*
X56835Y849002D01*
X58445D01*
G01X50358Y897088D02*
Y900188D01*
X51317D01*
X51623Y900033D01*
X51815Y899826D01*
X51892Y899413D01*
X51815Y899000D01*
X51585Y898741D01*
X51317Y898586D01*
X50358D01*
G01X51317D02*
X51892Y897088D01*
G01X54225D02*
Y900188D01*
X53765Y899568D01*
G01Y897088D02*
X54685D01*
G01X56597Y898380D02*
X56865Y898741D01*
X57095Y898948D01*
X57402Y899051D01*
X57670Y898948D01*
X57862Y898741D01*
X58015Y898431D01*
X58053Y898070D01*
X58015Y897760D01*
X57862Y897450D01*
X57632Y897191D01*
X57363Y897088D01*
X57057Y897191D01*
X56788Y897501D01*
X56635Y897966D01*
X56597Y898483D01*
X56673Y899155D01*
X56788Y899516D01*
X56980Y899878D01*
X57248Y900136D01*
X57517Y900188D01*
X57785Y900085D01*
X57977Y899826D01*
G01X59582Y897708D02*
X59812Y897346D01*
X60118Y897140D01*
X60463Y897088D01*
X60770Y897140D01*
X61077Y897398D01*
X61268Y897708D01*
X61307Y898018D01*
X61230Y898380D01*
X60962Y898638D01*
X60693Y898741D01*
X60348D01*
G01X60693D02*
X60923Y898896D01*
X61115Y899155D01*
X61192Y899465D01*
X61115Y899775D01*
X60923Y900033D01*
X60578Y900188D01*
X60233Y900136D01*
X59888Y899930D01*
G01X55539Y902596D02*
X49339D01*
Y905796D01*
X55539D01*
Y902596D01*
G01X62278Y911906D02*
X54778D01*
Y914146D01*
X55153Y914893D01*
X56028Y915453D01*
X57028Y915640D01*
X58028Y915453D01*
X58778Y914986D01*
X59153Y914146D01*
Y911906D01*
G01X62278Y919406D02*
X54778D01*
Y921740D01*
X55153Y922486D01*
X55653Y922953D01*
X56653Y923140D01*
X57653Y922953D01*
X58278Y922393D01*
X58653Y921740D01*
Y919406D01*
G01Y921740D02*
X62278Y923140D01*
G01Y930640D02*
Y926906D01*
X54778D01*
Y930640D01*
G01X58403Y929146D02*
Y926906D01*
G01X61278Y934313D02*
X61903Y935060D01*
X62278Y935900D01*
Y936646D01*
X61903Y937393D01*
X61278Y937953D01*
X60403Y938233D01*
X59528Y938046D01*
X58778Y937580D01*
X58278Y936740D01*
X58028Y935620D01*
X57528Y934966D01*
X56653Y934686D01*
X55778Y934873D01*
X55153Y935340D01*
X54778Y935993D01*
Y936646D01*
X55028Y937300D01*
X55653Y937860D01*
G01X61278Y941813D02*
X61903Y942560D01*
X62278Y943400D01*
Y944146D01*
X61903Y944893D01*
X61278Y945453D01*
X60403Y945733D01*
X59528Y945546D01*
X58778Y945080D01*
X58278Y944240D01*
X58028Y943120D01*
X57528Y942466D01*
X56653Y942186D01*
X55778Y942373D01*
X55153Y942840D01*
X54778Y943493D01*
Y944146D01*
X55028Y944800D01*
X55653Y945360D01*
G01X62278Y964500D02*
X54778D01*
Y968046D01*
G01X58403Y966740D02*
Y964500D01*
G01X54778Y972653D02*
Y974893D01*
G01Y973773D02*
X62278D01*
G01Y972653D02*
Y974893D01*
G01X54778Y981273D02*
X62278D01*
G01X54778Y979126D02*
Y983420D01*
G01X52387Y995165D02*
X52697Y995357D01*
X52904Y995587D01*
X53007Y995855D01*
X52904Y996162D01*
X52697Y996392D01*
X52387Y996622D01*
X51974Y996699D01*
X49907D01*
G01X50424Y998304D02*
X50114Y998534D01*
X49959Y998802D01*
X49907Y999109D01*
X50010Y999492D01*
X50269Y999760D01*
X50579Y999837D01*
X50889Y999799D01*
X51147Y999645D01*
X51664Y998879D01*
X52025Y998534D01*
X52542Y998304D01*
X53007Y998227D01*
Y999837D01*
G01X51715Y1001404D02*
X51354Y1001672D01*
X51147Y1001902D01*
X51044Y1002209D01*
X51147Y1002477D01*
X51354Y1002669D01*
X51664Y1002822D01*
X52025Y1002860D01*
X52335Y1002822D01*
X52645Y1002669D01*
X52904Y1002439D01*
X53007Y1002170D01*
X52904Y1001864D01*
X52594Y1001595D01*
X52129Y1001442D01*
X51612Y1001404D01*
X50940Y1001480D01*
X50579Y1001595D01*
X50217Y1001787D01*
X49959Y1002055D01*
X49907Y1002324D01*
X50010Y1002592D01*
X50269Y1002784D01*
G01X73184Y1053437D02*
X70084Y1054395D01*
X73184Y1055353D01*
G01X72099Y1055008D02*
Y1053782D01*
G01X73184Y1057495D02*
X73132Y1057763D01*
X72977Y1058070D01*
X72719Y1058262D01*
X72357Y1058338D01*
X71996Y1058262D01*
X71686Y1058032D01*
X71531Y1057687D01*
Y1057303D01*
X71427Y1057073D01*
X71169Y1056882D01*
X70807Y1056805D01*
X70446Y1056920D01*
X70187Y1057188D01*
X70084Y1057495D01*
X70187Y1057802D01*
X70446Y1058070D01*
X70807Y1058185D01*
X71169Y1058108D01*
X71427Y1057917D01*
X71531Y1057687D01*
Y1057303D01*
X71686Y1056958D01*
X71996Y1056728D01*
X72357Y1056652D01*
X72719Y1056728D01*
X72977Y1056920D01*
X73132Y1057227D01*
X73184Y1057495D01*
G01X70601Y1059867D02*
X70291Y1060097D01*
X70136Y1060365D01*
X70084Y1060672D01*
X70187Y1061055D01*
X70446Y1061323D01*
X70756Y1061400D01*
X71066Y1061362D01*
X71324Y1061208D01*
X71841Y1060442D01*
X72202Y1060097D01*
X72719Y1059867D01*
X73184Y1059790D01*
Y1061400D01*
G01X59925Y1200573D02*
Y1203673D01*
G01X61535D02*
Y1200573D01*
G01Y1202123D02*
X59925D01*
G01X64290Y1200573D02*
Y1203673D01*
X62872Y1201451D01*
X64788D01*
G01X62246Y1251260D02*
Y1254360D01*
X63205D01*
X63511Y1254205D01*
X63703Y1253998D01*
X63780Y1253585D01*
X63703Y1253172D01*
X63473Y1252913D01*
X63205Y1252758D01*
X62246D01*
G01X63205D02*
X63780Y1251260D01*
G01X66113D02*
Y1254360D01*
X65653Y1253740D01*
G01Y1251260D02*
X66573D01*
G01X69673D02*
Y1254360D01*
X68255Y1252138D01*
X70171D01*
G01X72313Y1254360D02*
X72006Y1254257D01*
X71776Y1253998D01*
X71623Y1253688D01*
X71508Y1253275D01*
X71470Y1252810D01*
X71508Y1252345D01*
X71623Y1251932D01*
X71776Y1251622D01*
X72006Y1251363D01*
X72313Y1251260D01*
X72620Y1251363D01*
X72850Y1251622D01*
X73003Y1251932D01*
X73118Y1252345D01*
X73156Y1252810D01*
X73118Y1253275D01*
X73003Y1253688D01*
X72850Y1253998D01*
X72620Y1254257D01*
X72313Y1254360D01*
G01X55938Y1251778D02*
X49738D01*
Y1254978D01*
X55938D01*
Y1251778D01*
G01X59878Y1260865D02*
Y1263965D01*
X60837D01*
X61143Y1263810D01*
X61335Y1263603D01*
X61412Y1263190D01*
X61335Y1262777D01*
X61105Y1262518D01*
X60837Y1262363D01*
X59878D01*
G01X60837D02*
X61412Y1260865D01*
G01X63745D02*
Y1263965D01*
X63285Y1263345D01*
G01Y1260865D02*
X64205D01*
G01X67305D02*
Y1263965D01*
X65887Y1261743D01*
X67803D01*
G01X70405Y1260865D02*
Y1263965D01*
X68987Y1261743D01*
X70903D01*
G01X55735Y1261503D02*
X49535D01*
Y1264703D01*
X55735D01*
Y1261503D01*
G01X60075Y1255734D02*
Y1258834D01*
X61034D01*
X61340Y1258679D01*
X61532Y1258472D01*
X61609Y1258059D01*
X61532Y1257646D01*
X61302Y1257387D01*
X61034Y1257232D01*
X60075D01*
G01X61034D02*
X61609Y1255734D01*
G01X63942D02*
Y1258834D01*
X63482Y1258214D01*
G01Y1255734D02*
X64402D01*
G01X67502D02*
Y1258834D01*
X66084Y1256612D01*
X68000D01*
G01X70142Y1255734D02*
Y1258834D01*
X69682Y1258214D01*
G01Y1255734D02*
X70602D01*
G01X55802Y1256033D02*
X49602D01*
Y1259233D01*
X55802D01*
Y1256033D01*
G01X59876Y1278240D02*
Y1281340D01*
X60835D01*
X61141Y1281185D01*
X61333Y1280978D01*
X61410Y1280565D01*
X61333Y1280152D01*
X61103Y1279893D01*
X60835Y1279738D01*
X59876D01*
G01X60835D02*
X61410Y1278240D01*
G01X63743D02*
Y1281340D01*
X63283Y1280720D01*
G01Y1278240D02*
X64203D01*
G01X67303D02*
Y1281340D01*
X65885Y1279118D01*
X67801D01*
G01X69215Y1280823D02*
X69445Y1281133D01*
X69713Y1281288D01*
X70020Y1281340D01*
X70403Y1281237D01*
X70671Y1280978D01*
X70748Y1280668D01*
X70710Y1280358D01*
X70556Y1280100D01*
X69790Y1279583D01*
X69445Y1279222D01*
X69215Y1278705D01*
X69138Y1278240D01*
X70748D01*
G01X56107Y1278183D02*
X49907D01*
Y1281383D01*
X56107D01*
Y1278183D01*
G01X60075Y1265536D02*
Y1268636D01*
X61034D01*
X61340Y1268481D01*
X61532Y1268274D01*
X61609Y1267861D01*
X61532Y1267448D01*
X61302Y1267189D01*
X61034Y1267034D01*
X60075D01*
G01X61034D02*
X61609Y1265536D01*
G01X63942D02*
Y1268636D01*
X63482Y1268016D01*
G01Y1265536D02*
X64402D01*
G01X67502D02*
Y1268636D01*
X66084Y1266414D01*
X68000D01*
G01X69299Y1266156D02*
X69529Y1265794D01*
X69835Y1265588D01*
X70180Y1265536D01*
X70487Y1265588D01*
X70794Y1265846D01*
X70985Y1266156D01*
X71024Y1266466D01*
X70947Y1266828D01*
X70679Y1267086D01*
X70410Y1267189D01*
X70065D01*
G01X70410D02*
X70640Y1267344D01*
X70832Y1267603D01*
X70909Y1267913D01*
X70832Y1268223D01*
X70640Y1268481D01*
X70295Y1268636D01*
X69950Y1268584D01*
X69605Y1268378D01*
G01X56073Y1265690D02*
X49873D01*
Y1268890D01*
X56073D01*
Y1265690D01*
G01X60131Y1282330D02*
Y1285430D01*
X61090D01*
X61396Y1285275D01*
X61588Y1285068D01*
X61665Y1284655D01*
X61588Y1284242D01*
X61358Y1283983D01*
X61090Y1283828D01*
X60131D01*
G01X61090D02*
X61665Y1282330D01*
G01X63998D02*
Y1285430D01*
X63538Y1284810D01*
G01Y1282330D02*
X64458D01*
G01X67558D02*
Y1285430D01*
X66140Y1283208D01*
X68056D01*
G01X69355Y1282795D02*
X69585Y1282537D01*
X69853Y1282382D01*
X70198Y1282330D01*
X70543Y1282433D01*
X70811Y1282640D01*
X71003Y1283002D01*
X71041Y1283415D01*
X70965Y1283828D01*
X70773Y1284087D01*
X70505Y1284293D01*
X70236Y1284345D01*
X69968Y1284293D01*
X69623Y1284087D01*
X69738Y1285430D01*
X70773D01*
G01X55971Y1282438D02*
X49771D01*
Y1285638D01*
X55971D01*
Y1282438D01*
G01X59679Y1274095D02*
Y1277195D01*
X60638D01*
X60944Y1277040D01*
X61136Y1276833D01*
X61213Y1276420D01*
X61136Y1276007D01*
X60906Y1275748D01*
X60638Y1275593D01*
X59679D01*
G01X60638D02*
X61213Y1274095D01*
G01X63546D02*
Y1277195D01*
X63086Y1276575D01*
G01Y1274095D02*
X64006D01*
G01X67106D02*
Y1277195D01*
X65688Y1274973D01*
X67604D01*
G01X69018Y1275387D02*
X69286Y1275748D01*
X69516Y1275955D01*
X69823Y1276058D01*
X70091Y1275955D01*
X70283Y1275748D01*
X70436Y1275438D01*
X70474Y1275077D01*
X70436Y1274767D01*
X70283Y1274457D01*
X70053Y1274198D01*
X69784Y1274095D01*
X69478Y1274198D01*
X69209Y1274508D01*
X69056Y1274973D01*
X69018Y1275490D01*
X69094Y1276162D01*
X69209Y1276523D01*
X69401Y1276885D01*
X69669Y1277143D01*
X69938Y1277195D01*
X70206Y1277092D01*
X70398Y1276833D01*
G01X56107Y1274030D02*
X49907D01*
Y1277230D01*
X56107D01*
Y1274030D01*
G01X59812Y1269746D02*
Y1272846D01*
X60771D01*
X61077Y1272691D01*
X61269Y1272484D01*
X61346Y1272071D01*
X61269Y1271658D01*
X61039Y1271399D01*
X60771Y1271244D01*
X59812D01*
G01X60771D02*
X61346Y1269746D01*
G01X63679D02*
Y1272846D01*
X63219Y1272226D01*
G01Y1269746D02*
X64139D01*
G01X67239D02*
Y1272846D01*
X65821Y1270624D01*
X67737D01*
G01X69802Y1269746D02*
X69879Y1270418D01*
X69994Y1270986D01*
X70147Y1271503D01*
X70339Y1272071D01*
X70646Y1272846D01*
X69112D01*
G01X56006Y1269944D02*
X49806D01*
Y1273144D01*
X56006D01*
Y1269944D01*
G01X61069Y1287046D02*
X57969D01*
Y1288005D01*
X58124Y1288311D01*
X58331Y1288503D01*
X58744Y1288580D01*
X59157Y1288503D01*
X59416Y1288273D01*
X59571Y1288005D01*
Y1287046D01*
G01Y1288005D02*
X61069Y1288580D01*
G01X60449Y1290070D02*
X60811Y1290300D01*
X61017Y1290606D01*
X61069Y1290951D01*
X61017Y1291258D01*
X60759Y1291565D01*
X60449Y1291756D01*
X60139Y1291795D01*
X59777Y1291718D01*
X59519Y1291450D01*
X59416Y1291181D01*
Y1290836D01*
G01Y1291181D02*
X59261Y1291411D01*
X59002Y1291603D01*
X58692Y1291680D01*
X58382Y1291603D01*
X58124Y1291411D01*
X57969Y1291066D01*
X58021Y1290721D01*
X58227Y1290376D01*
G01X60604Y1293170D02*
X60862Y1293400D01*
X61017Y1293668D01*
X61069Y1294013D01*
X60966Y1294358D01*
X60759Y1294626D01*
X60397Y1294818D01*
X59984Y1294856D01*
X59571Y1294780D01*
X59312Y1294588D01*
X59106Y1294320D01*
X59054Y1294051D01*
X59106Y1293783D01*
X59312Y1293438D01*
X57969Y1293553D01*
Y1294588D01*
G01X52648Y1286980D02*
X49548D01*
Y1287939D01*
X49703Y1288245D01*
X49910Y1288437D01*
X50323Y1288514D01*
X50736Y1288437D01*
X50995Y1288207D01*
X51150Y1287939D01*
Y1286980D01*
G01Y1287939D02*
X52648Y1288514D01*
G01X52028Y1290004D02*
X52390Y1290234D01*
X52596Y1290540D01*
X52648Y1290885D01*
X52596Y1291192D01*
X52338Y1291499D01*
X52028Y1291690D01*
X51718Y1291729D01*
X51356Y1291652D01*
X51098Y1291384D01*
X50995Y1291115D01*
Y1290770D01*
G01Y1291115D02*
X50840Y1291345D01*
X50581Y1291537D01*
X50271Y1291614D01*
X49961Y1291537D01*
X49703Y1291345D01*
X49548Y1291000D01*
X49600Y1290655D01*
X49806Y1290310D01*
G01X51356Y1293219D02*
X50995Y1293487D01*
X50788Y1293717D01*
X50685Y1294024D01*
X50788Y1294292D01*
X50995Y1294484D01*
X51305Y1294637D01*
X51666Y1294675D01*
X51976Y1294637D01*
X52286Y1294484D01*
X52545Y1294254D01*
X52648Y1293985D01*
X52545Y1293679D01*
X52235Y1293410D01*
X51770Y1293257D01*
X51253Y1293219D01*
X50581Y1293295D01*
X50220Y1293410D01*
X49858Y1293602D01*
X49600Y1293870D01*
X49548Y1294139D01*
X49651Y1294407D01*
X49910Y1294599D01*
G01X74226Y1286880D02*
X71126D01*
Y1287839D01*
X71281Y1288145D01*
X71488Y1288337D01*
X71901Y1288414D01*
X72314Y1288337D01*
X72573Y1288107D01*
X72728Y1287839D01*
Y1286880D01*
G01Y1287839D02*
X74226Y1288414D01*
G01X73606Y1289904D02*
X73968Y1290134D01*
X74174Y1290440D01*
X74226Y1290785D01*
X74174Y1291092D01*
X73916Y1291399D01*
X73606Y1291590D01*
X73296Y1291629D01*
X72934Y1291552D01*
X72676Y1291284D01*
X72573Y1291015D01*
Y1290670D01*
G01Y1291015D02*
X72418Y1291245D01*
X72159Y1291437D01*
X71849Y1291514D01*
X71539Y1291437D01*
X71281Y1291245D01*
X71126Y1290900D01*
X71178Y1290555D01*
X71384Y1290210D01*
G01X74226Y1294307D02*
X71126D01*
X73348Y1292889D01*
Y1294805D01*
G01X69885Y1286881D02*
X66785D01*
Y1287840D01*
X66940Y1288146D01*
X67147Y1288338D01*
X67560Y1288415D01*
X67973Y1288338D01*
X68232Y1288108D01*
X68387Y1287840D01*
Y1286881D01*
G01Y1287840D02*
X69885Y1288415D01*
G01X69265Y1289905D02*
X69627Y1290135D01*
X69833Y1290441D01*
X69885Y1290786D01*
X69833Y1291093D01*
X69575Y1291400D01*
X69265Y1291591D01*
X68955Y1291630D01*
X68593Y1291553D01*
X68335Y1291285D01*
X68232Y1291016D01*
Y1290671D01*
G01Y1291016D02*
X68077Y1291246D01*
X67818Y1291438D01*
X67508Y1291515D01*
X67198Y1291438D01*
X66940Y1291246D01*
X66785Y1290901D01*
X66837Y1290556D01*
X67043Y1290211D01*
G01X69885Y1293771D02*
X69213Y1293848D01*
X68645Y1293963D01*
X68128Y1294116D01*
X67560Y1294308D01*
X66785Y1294615D01*
Y1293081D01*
G01X65378Y1287046D02*
X62278D01*
Y1288005D01*
X62433Y1288311D01*
X62640Y1288503D01*
X63053Y1288580D01*
X63466Y1288503D01*
X63725Y1288273D01*
X63880Y1288005D01*
Y1287046D01*
G01Y1288005D02*
X65378Y1288580D01*
G01X64758Y1290070D02*
X65120Y1290300D01*
X65326Y1290606D01*
X65378Y1290951D01*
X65326Y1291258D01*
X65068Y1291565D01*
X64758Y1291756D01*
X64448Y1291795D01*
X64086Y1291718D01*
X63828Y1291450D01*
X63725Y1291181D01*
Y1290836D01*
G01Y1291181D02*
X63570Y1291411D01*
X63311Y1291603D01*
X63001Y1291680D01*
X62691Y1291603D01*
X62433Y1291411D01*
X62278Y1291066D01*
X62330Y1290721D01*
X62536Y1290376D01*
G01X65378Y1294013D02*
X65326Y1294281D01*
X65171Y1294588D01*
X64913Y1294780D01*
X64551Y1294856D01*
X64190Y1294780D01*
X63880Y1294550D01*
X63725Y1294205D01*
Y1293821D01*
X63621Y1293591D01*
X63363Y1293400D01*
X63001Y1293323D01*
X62640Y1293438D01*
X62381Y1293706D01*
X62278Y1294013D01*
X62381Y1294320D01*
X62640Y1294588D01*
X63001Y1294703D01*
X63363Y1294626D01*
X63621Y1294435D01*
X63725Y1294205D01*
Y1293821D01*
X63880Y1293476D01*
X64190Y1293246D01*
X64551Y1293170D01*
X64913Y1293246D01*
X65171Y1293438D01*
X65326Y1293745D01*
X65378Y1294013D01*
G01X56860Y1286981D02*
X53760D01*
Y1287940D01*
X53915Y1288246D01*
X54122Y1288438D01*
X54535Y1288515D01*
X54948Y1288438D01*
X55207Y1288208D01*
X55362Y1287940D01*
Y1286981D01*
G01Y1287940D02*
X56860Y1288515D01*
G01X56240Y1290005D02*
X56602Y1290235D01*
X56808Y1290541D01*
X56860Y1290886D01*
X56808Y1291193D01*
X56550Y1291500D01*
X56240Y1291691D01*
X55930Y1291730D01*
X55568Y1291653D01*
X55310Y1291385D01*
X55207Y1291116D01*
Y1290771D01*
G01Y1291116D02*
X55052Y1291346D01*
X54793Y1291538D01*
X54483Y1291615D01*
X54173Y1291538D01*
X53915Y1291346D01*
X53760Y1291001D01*
X53812Y1290656D01*
X54018Y1290311D01*
G01X56498Y1293296D02*
X56757Y1293565D01*
X56860Y1293871D01*
X56757Y1294178D01*
X56447Y1294446D01*
X55982Y1294638D01*
X55517Y1294715D01*
X54948D01*
X54483Y1294638D01*
X54070Y1294446D01*
X53863Y1294216D01*
X53760Y1293948D01*
X53863Y1293641D01*
X54070Y1293411D01*
X54380Y1293258D01*
X54793Y1293181D01*
X55155Y1293258D01*
X55517Y1293450D01*
X55723Y1293680D01*
X55775Y1293948D01*
X55672Y1294255D01*
X55413Y1294485D01*
X54948Y1294715D01*
G01X60352Y1304271D02*
Y1298071D01*
X57152D01*
Y1304271D01*
X60352D01*
G01X73509Y1304105D02*
Y1297905D01*
X70309D01*
Y1304105D01*
X73509D01*
G01X69168Y1304106D02*
Y1297906D01*
X65968D01*
Y1304106D01*
X69168D01*
G01X64661Y1304271D02*
Y1298071D01*
X61461D01*
Y1304271D01*
X64661D01*
G01X56143Y1304206D02*
Y1298006D01*
X52943D01*
Y1304206D01*
X56143D01*
G01X56373Y1339870D02*
Y1337648D01*
X56526Y1337183D01*
X56833Y1336873D01*
X57216Y1336770D01*
X57599Y1336873D01*
X57906Y1337183D01*
X58059Y1337648D01*
Y1339870D01*
G01X60316Y1336770D02*
Y1339870D01*
X59856Y1339250D01*
G01Y1336770D02*
X60776D01*
G01X64366Y1331303D02*
X60123Y1335546D01*
X57166D01*
Y1315860D01*
X71566D01*
Y1335546D01*
X68609D01*
X64366Y1331303D01*
G01X54406Y1346086D02*
X51306D01*
Y1347045D01*
X51461Y1347351D01*
X51668Y1347543D01*
X52081Y1347620D01*
X52494Y1347543D01*
X52753Y1347313D01*
X52908Y1347045D01*
Y1346086D01*
G01Y1347045D02*
X54406Y1347620D01*
G01Y1350413D02*
X51306D01*
X53528Y1348995D01*
Y1350911D01*
G01X54406Y1353053D02*
X51306D01*
X51926Y1352593D01*
G01X54406D02*
Y1353513D01*
G01X53827Y1343497D02*
Y1337297D01*
X50627D01*
Y1343497D01*
X53827D01*
G01X62092Y1354148D02*
X57092D01*
Y1355668D01*
X57342Y1356175D01*
X57925Y1356555D01*
X58592Y1356682D01*
X59259Y1356555D01*
X59759Y1356238D01*
X60009Y1355668D01*
Y1354148D01*
G01X62092Y1359248D02*
X57092D01*
Y1360832D01*
X57342Y1361338D01*
X57675Y1361655D01*
X58342Y1361782D01*
X59009Y1361655D01*
X59425Y1361275D01*
X59675Y1360832D01*
Y1359248D01*
G01Y1360832D02*
X62092Y1361782D01*
G01Y1366882D02*
Y1364348D01*
X57092D01*
Y1366882D01*
G01X59509Y1365868D02*
Y1364348D01*
G01X61425Y1369385D02*
X61842Y1369892D01*
X62092Y1370462D01*
Y1370968D01*
X61842Y1371475D01*
X61425Y1371855D01*
X60842Y1372045D01*
X60259Y1371918D01*
X59759Y1371602D01*
X59425Y1371032D01*
X59259Y1370272D01*
X58925Y1369828D01*
X58342Y1369638D01*
X57759Y1369765D01*
X57342Y1370082D01*
X57092Y1370525D01*
Y1370968D01*
X57259Y1371412D01*
X57675Y1371792D01*
G01X61425Y1374485D02*
X61842Y1374992D01*
X62092Y1375562D01*
Y1376068D01*
X61842Y1376575D01*
X61425Y1376955D01*
X60842Y1377145D01*
X60259Y1377018D01*
X59759Y1376702D01*
X59425Y1376132D01*
X59259Y1375372D01*
X58925Y1374928D01*
X58342Y1374738D01*
X57759Y1374865D01*
X57342Y1375182D01*
X57092Y1375625D01*
Y1376068D01*
X57259Y1376512D01*
X57675Y1376892D01*
G01X62092Y1389912D02*
X57092D01*
Y1392318D01*
G01X59509Y1391432D02*
Y1389912D01*
G01X57092Y1395455D02*
Y1396975D01*
G01Y1396215D02*
X62092D01*
G01Y1395455D02*
Y1396975D01*
G01X57092Y1401315D02*
X62092D01*
G01X57092Y1399858D02*
Y1402772D01*
G01X52364Y1381707D02*
X52674Y1381899D01*
X52881Y1382129D01*
X52984Y1382397D01*
X52881Y1382704D01*
X52674Y1382934D01*
X52364Y1383164D01*
X51951Y1383241D01*
X49884D01*
G01X50401Y1384846D02*
X50091Y1385076D01*
X49936Y1385344D01*
X49884Y1385651D01*
X49987Y1386034D01*
X50246Y1386302D01*
X50556Y1386379D01*
X50866Y1386341D01*
X51124Y1386187D01*
X51641Y1385421D01*
X52002Y1385076D01*
X52519Y1384846D01*
X52984Y1384769D01*
Y1386379D01*
G01X52519Y1387831D02*
X52777Y1388061D01*
X52932Y1388329D01*
X52984Y1388674D01*
X52881Y1389019D01*
X52674Y1389287D01*
X52312Y1389479D01*
X51899Y1389517D01*
X51486Y1389441D01*
X51227Y1389249D01*
X51021Y1388981D01*
X50969Y1388712D01*
X51021Y1388444D01*
X51227Y1388099D01*
X49884Y1388214D01*
Y1389249D01*
G01X65123Y1557873D02*
X65391Y1557925D01*
X65698Y1558080D01*
X65890Y1558338D01*
X65966Y1558700D01*
X65890Y1559061D01*
X65660Y1559371D01*
X65315Y1559526D01*
X64931D01*
X64701Y1559630D01*
X64510Y1559888D01*
X64433Y1560250D01*
X64548Y1560611D01*
X64816Y1560870D01*
X65123Y1560973D01*
X65430Y1560870D01*
X65698Y1560611D01*
X65813Y1560250D01*
X65736Y1559888D01*
X65545Y1559630D01*
X65315Y1559526D01*
X64931D01*
X64586Y1559371D01*
X64356Y1559061D01*
X64280Y1558700D01*
X64356Y1558338D01*
X64548Y1558080D01*
X64855Y1557925D01*
X65123Y1557873D01*
G01X56035Y1557572D02*
X56112Y1558244D01*
X56227Y1558812D01*
X56380Y1559329D01*
X56572Y1559897D01*
X56879Y1560672D01*
X55345D01*
G01X50454Y1627287D02*
X70215D01*
Y1562721D01*
X50454D01*
G01X65274Y1631658D02*
X65504Y1631968D01*
X65772Y1632123D01*
X66079Y1632175D01*
X66462Y1632072D01*
X66730Y1631813D01*
X66807Y1631503D01*
X66769Y1631193D01*
X66615Y1630935D01*
X65849Y1630418D01*
X65504Y1630057D01*
X65274Y1629540D01*
X65197Y1629075D01*
X66807D01*
G01X58620Y1629275D02*
Y1632375D01*
X58160Y1631755D01*
G01Y1629275D02*
X59080D01*
G01X61993Y1750207D02*
X61763Y1750362D01*
X61495Y1750465D01*
X61188D01*
X60843Y1750310D01*
X60575Y1750052D01*
X60383Y1749742D01*
X60230Y1749225D01*
X60192Y1748760D01*
X60268Y1748295D01*
X60383Y1747985D01*
X60613Y1747675D01*
X60882Y1747468D01*
X61150Y1747365D01*
X61418D01*
X61687Y1747468D01*
X61917Y1747623D01*
X62108Y1747830D01*
G01X64250Y1747365D02*
X64518Y1747417D01*
X64825Y1747572D01*
X65017Y1747830D01*
X65093Y1748192D01*
X65017Y1748553D01*
X64787Y1748863D01*
X64442Y1749018D01*
X64058D01*
X63828Y1749122D01*
X63637Y1749380D01*
X63560Y1749742D01*
X63675Y1750103D01*
X63943Y1750362D01*
X64250Y1750465D01*
X64557Y1750362D01*
X64825Y1750103D01*
X64940Y1749742D01*
X64863Y1749380D01*
X64672Y1749122D01*
X64442Y1749018D01*
X64058D01*
X63713Y1748863D01*
X63483Y1748553D01*
X63407Y1748192D01*
X63483Y1747830D01*
X63675Y1747572D01*
X63982Y1747417D01*
X64250Y1747365D01*
G01X67273D02*
X67350Y1748037D01*
X67465Y1748605D01*
X67618Y1749122D01*
X67810Y1749690D01*
X68117Y1750465D01*
X66583D01*
G01X61844Y1745899D02*
X61614Y1746054D01*
X61346Y1746157D01*
X61039D01*
X60694Y1746002D01*
X60426Y1745744D01*
X60234Y1745434D01*
X60081Y1744917D01*
X60043Y1744452D01*
X60119Y1743987D01*
X60234Y1743677D01*
X60464Y1743367D01*
X60733Y1743160D01*
X61001Y1743057D01*
X61269D01*
X61538Y1743160D01*
X61768Y1743315D01*
X61959Y1743522D01*
G01X64101Y1743057D02*
X64369Y1743109D01*
X64676Y1743264D01*
X64868Y1743522D01*
X64944Y1743884D01*
X64868Y1744245D01*
X64638Y1744555D01*
X64293Y1744710D01*
X63909D01*
X63679Y1744814D01*
X63488Y1745072D01*
X63411Y1745434D01*
X63526Y1745795D01*
X63794Y1746054D01*
X64101Y1746157D01*
X64408Y1746054D01*
X64676Y1745795D01*
X64791Y1745434D01*
X64714Y1745072D01*
X64523Y1744814D01*
X64293Y1744710D01*
X63909D01*
X63564Y1744555D01*
X63334Y1744245D01*
X63258Y1743884D01*
X63334Y1743522D01*
X63526Y1743264D01*
X63833Y1743109D01*
X64101Y1743057D01*
G01X66473Y1744349D02*
X66741Y1744710D01*
X66971Y1744917D01*
X67278Y1745020D01*
X67546Y1744917D01*
X67738Y1744710D01*
X67891Y1744400D01*
X67929Y1744039D01*
X67891Y1743729D01*
X67738Y1743419D01*
X67508Y1743160D01*
X67239Y1743057D01*
X66933Y1743160D01*
X66664Y1743470D01*
X66511Y1743935D01*
X66473Y1744452D01*
X66549Y1745124D01*
X66664Y1745485D01*
X66856Y1745847D01*
X67124Y1746105D01*
X67393Y1746157D01*
X67661Y1746054D01*
X67853Y1745795D01*
G01X61771Y1741707D02*
X61541Y1741862D01*
X61273Y1741965D01*
X60966D01*
X60621Y1741810D01*
X60353Y1741552D01*
X60161Y1741242D01*
X60008Y1740725D01*
X59970Y1740260D01*
X60046Y1739795D01*
X60161Y1739485D01*
X60391Y1739175D01*
X60660Y1738968D01*
X60928Y1738865D01*
X61196D01*
X61465Y1738968D01*
X61695Y1739123D01*
X61886Y1739330D01*
G01X64028Y1738865D02*
X64296Y1738917D01*
X64603Y1739072D01*
X64795Y1739330D01*
X64871Y1739692D01*
X64795Y1740053D01*
X64565Y1740363D01*
X64220Y1740518D01*
X63836D01*
X63606Y1740622D01*
X63415Y1740880D01*
X63338Y1741242D01*
X63453Y1741603D01*
X63721Y1741862D01*
X64028Y1741965D01*
X64335Y1741862D01*
X64603Y1741603D01*
X64718Y1741242D01*
X64641Y1740880D01*
X64450Y1740622D01*
X64220Y1740518D01*
X63836D01*
X63491Y1740363D01*
X63261Y1740053D01*
X63185Y1739692D01*
X63261Y1739330D01*
X63453Y1739072D01*
X63760Y1738917D01*
X64028Y1738865D01*
G01X66285Y1739330D02*
X66515Y1739072D01*
X66783Y1738917D01*
X67128Y1738865D01*
X67473Y1738968D01*
X67741Y1739175D01*
X67933Y1739537D01*
X67971Y1739950D01*
X67895Y1740363D01*
X67703Y1740622D01*
X67435Y1740828D01*
X67166Y1740880D01*
X66898Y1740828D01*
X66553Y1740622D01*
X66668Y1741965D01*
X67703D01*
G01X64029Y1767535D02*
Y1774135D01*
G01X71529Y1774235D02*
Y1767435D01*
X56529D01*
Y1774235D01*
X71529D01*
G01X64029Y1759682D02*
Y1766282D01*
G01X71529Y1766382D02*
Y1759582D01*
X56529D01*
Y1766382D01*
X71529D01*
G01X64029Y1751871D02*
Y1758471D01*
G01X71529Y1758571D02*
Y1751771D01*
X56529D01*
Y1758571D01*
X71529D01*
G01X58090Y1793473D02*
X57860Y1793628D01*
X57592Y1793731D01*
X57285D01*
X56940Y1793576D01*
X56672Y1793318D01*
X56480Y1793008D01*
X56327Y1792491D01*
X56289Y1792026D01*
X56365Y1791561D01*
X56480Y1791251D01*
X56710Y1790941D01*
X56979Y1790734D01*
X57247Y1790631D01*
X57515D01*
X57784Y1790734D01*
X58014Y1790889D01*
X58205Y1791096D01*
G01X59695Y1790993D02*
X59964Y1790734D01*
X60270Y1790631D01*
X60577Y1790734D01*
X60845Y1791044D01*
X61037Y1791509D01*
X61114Y1791974D01*
Y1792543D01*
X61037Y1793008D01*
X60845Y1793421D01*
X60615Y1793628D01*
X60347Y1793731D01*
X60040Y1793628D01*
X59810Y1793421D01*
X59657Y1793111D01*
X59580Y1792698D01*
X59657Y1792336D01*
X59849Y1791974D01*
X60079Y1791768D01*
X60347Y1791716D01*
X60654Y1791819D01*
X60884Y1792078D01*
X61114Y1792543D01*
G01X63447Y1793731D02*
X63140Y1793628D01*
X62910Y1793369D01*
X62757Y1793059D01*
X62642Y1792646D01*
X62604Y1792181D01*
X62642Y1791716D01*
X62757Y1791303D01*
X62910Y1790993D01*
X63140Y1790734D01*
X63447Y1790631D01*
X63754Y1790734D01*
X63984Y1790993D01*
X64137Y1791303D01*
X64252Y1791716D01*
X64290Y1792181D01*
X64252Y1792646D01*
X64137Y1793059D01*
X63984Y1793369D01*
X63754Y1793628D01*
X63447Y1793731D01*
G01X61184Y1776871D02*
Y1779871D01*
G01X58084Y1779971D02*
X64284D01*
Y1776771D01*
X58084D01*
Y1779971D01*
G01X56060Y1795209D02*
Y1798309D01*
X57019D01*
X57325Y1798154D01*
X57517Y1797947D01*
X57594Y1797534D01*
X57517Y1797121D01*
X57287Y1796862D01*
X57019Y1796707D01*
X56060D01*
G01X57019D02*
X57594Y1795209D01*
G01X59927D02*
Y1798309D01*
X59467Y1797689D01*
G01Y1795209D02*
X60387D01*
G01X62184Y1795674D02*
X62414Y1795416D01*
X62682Y1795261D01*
X63027Y1795209D01*
X63372Y1795312D01*
X63640Y1795519D01*
X63832Y1795881D01*
X63870Y1796294D01*
X63794Y1796707D01*
X63602Y1796966D01*
X63334Y1797172D01*
X63065Y1797224D01*
X62797Y1797172D01*
X62452Y1796966D01*
X62567Y1798309D01*
X63602D01*
G01X66587Y1795209D02*
Y1798309D01*
X65169Y1796087D01*
X67085D01*
G01X64162Y1781385D02*
X57962D01*
Y1784585D01*
X64162D01*
Y1781385D01*
G01X71376Y1787443D02*
G03I-1000J0D01*
G01X67976Y1796543D02*
X87776D01*
Y1785343D01*
X67976D01*
Y1789143D01*
X69776Y1790943D01*
X67976Y1792743D01*
Y1796543D01*
G01X62183Y1806543D02*
Y1804321D01*
X62336Y1803856D01*
X62643Y1803546D01*
X63026Y1803443D01*
X63409Y1803546D01*
X63716Y1803856D01*
X63869Y1804321D01*
Y1806543D01*
G01X65398Y1806026D02*
X65628Y1806336D01*
X65896Y1806491D01*
X66203Y1806543D01*
X66586Y1806440D01*
X66854Y1806181D01*
X66931Y1805871D01*
X66893Y1805561D01*
X66739Y1805303D01*
X65973Y1804786D01*
X65628Y1804425D01*
X65398Y1803908D01*
X65321Y1803443D01*
X66931D01*
G01X87914Y31010D02*
Y34110D01*
X88873D01*
X89179Y33955D01*
X89371Y33748D01*
X89448Y33335D01*
X89371Y32922D01*
X89141Y32663D01*
X88873Y32508D01*
X87914D01*
G01X88873D02*
X89448Y31010D01*
G01X92241D02*
Y34110D01*
X90823Y31888D01*
X92739D01*
G01X94038Y31630D02*
X94268Y31268D01*
X94574Y31062D01*
X94919Y31010D01*
X95226Y31062D01*
X95533Y31320D01*
X95724Y31630D01*
X95763Y31940D01*
X95686Y32302D01*
X95418Y32560D01*
X95149Y32663D01*
X94804D01*
G01X95149D02*
X95379Y32818D01*
X95571Y33077D01*
X95648Y33387D01*
X95571Y33697D01*
X95379Y33955D01*
X95034Y34110D01*
X94689Y34058D01*
X94344Y33852D01*
G01X87914Y26477D02*
Y29577D01*
X88873D01*
X89179Y29422D01*
X89371Y29215D01*
X89448Y28802D01*
X89371Y28389D01*
X89141Y28130D01*
X88873Y27975D01*
X87914D01*
G01X88873D02*
X89448Y26477D01*
G01X91053Y27769D02*
X91321Y28130D01*
X91551Y28337D01*
X91858Y28440D01*
X92126Y28337D01*
X92318Y28130D01*
X92471Y27820D01*
X92509Y27459D01*
X92471Y27149D01*
X92318Y26839D01*
X92088Y26580D01*
X91819Y26477D01*
X91513Y26580D01*
X91244Y26890D01*
X91091Y27355D01*
X91053Y27872D01*
X91129Y28544D01*
X91244Y28905D01*
X91436Y29267D01*
X91704Y29525D01*
X91973Y29577D01*
X92241Y29474D01*
X92433Y29215D01*
G01X94153Y29060D02*
X94383Y29370D01*
X94651Y29525D01*
X94958Y29577D01*
X95341Y29474D01*
X95609Y29215D01*
X95686Y28905D01*
X95648Y28595D01*
X95494Y28337D01*
X94728Y27820D01*
X94383Y27459D01*
X94153Y26942D01*
X94076Y26477D01*
X95686D01*
G01X87829Y22360D02*
Y25460D01*
X88788D01*
X89094Y25305D01*
X89286Y25098D01*
X89363Y24685D01*
X89286Y24272D01*
X89056Y24013D01*
X88788Y23858D01*
X87829D01*
G01X88788D02*
X89363Y22360D01*
G01X90968Y23652D02*
X91236Y24013D01*
X91466Y24220D01*
X91773Y24323D01*
X92041Y24220D01*
X92233Y24013D01*
X92386Y23703D01*
X92424Y23342D01*
X92386Y23032D01*
X92233Y22722D01*
X92003Y22463D01*
X91734Y22360D01*
X91428Y22463D01*
X91159Y22773D01*
X91006Y23238D01*
X90968Y23755D01*
X91044Y24427D01*
X91159Y24788D01*
X91351Y25150D01*
X91619Y25408D01*
X91888Y25460D01*
X92156Y25357D01*
X92348Y25098D01*
G01X95256Y22360D02*
Y25460D01*
X93838Y23238D01*
X95754D01*
G01X91259Y45559D02*
Y48659D01*
X92218D01*
X92524Y48504D01*
X92716Y48297D01*
X92793Y47884D01*
X92716Y47471D01*
X92486Y47212D01*
X92218Y47057D01*
X91259D01*
G01X92218D02*
X92793Y45559D01*
G01X95586D02*
Y48659D01*
X94168Y46437D01*
X96084D01*
G01X97574Y45921D02*
X97843Y45662D01*
X98149Y45559D01*
X98456Y45662D01*
X98724Y45972D01*
X98916Y46437D01*
X98993Y46902D01*
Y47471D01*
X98916Y47936D01*
X98724Y48349D01*
X98494Y48556D01*
X98226Y48659D01*
X97919Y48556D01*
X97689Y48349D01*
X97536Y48039D01*
X97459Y47626D01*
X97536Y47264D01*
X97728Y46902D01*
X97958Y46696D01*
X98226Y46644D01*
X98533Y46747D01*
X98763Y47006D01*
X98993Y47471D01*
G01X91062Y41678D02*
Y44778D01*
X92021D01*
X92327Y44623D01*
X92519Y44416D01*
X92596Y44003D01*
X92519Y43590D01*
X92289Y43331D01*
X92021Y43176D01*
X91062D01*
G01X92021D02*
X92596Y41678D01*
G01X94086Y42143D02*
X94316Y41885D01*
X94584Y41730D01*
X94929Y41678D01*
X95274Y41781D01*
X95542Y41988D01*
X95734Y42350D01*
X95772Y42763D01*
X95696Y43176D01*
X95504Y43435D01*
X95236Y43641D01*
X94967Y43693D01*
X94699Y43641D01*
X94354Y43435D01*
X94469Y44778D01*
X95504D01*
G01X98029D02*
X97722Y44675D01*
X97492Y44416D01*
X97339Y44106D01*
X97224Y43693D01*
X97186Y43228D01*
X97224Y42763D01*
X97339Y42350D01*
X97492Y42040D01*
X97722Y41781D01*
X98029Y41678D01*
X98336Y41781D01*
X98566Y42040D01*
X98719Y42350D01*
X98834Y42763D01*
X98872Y43228D01*
X98834Y43693D01*
X98719Y44106D01*
X98566Y44416D01*
X98336Y44675D01*
X98029Y44778D01*
G01X87914Y35595D02*
Y38695D01*
X88873D01*
X89179Y38540D01*
X89371Y38333D01*
X89448Y37920D01*
X89371Y37507D01*
X89141Y37248D01*
X88873Y37093D01*
X87914D01*
G01X88873D02*
X89448Y35595D01*
G01X91053Y36887D02*
X91321Y37248D01*
X91551Y37455D01*
X91858Y37558D01*
X92126Y37455D01*
X92318Y37248D01*
X92471Y36938D01*
X92509Y36577D01*
X92471Y36267D01*
X92318Y35957D01*
X92088Y35698D01*
X91819Y35595D01*
X91513Y35698D01*
X91244Y36008D01*
X91091Y36473D01*
X91053Y36990D01*
X91129Y37662D01*
X91244Y38023D01*
X91436Y38385D01*
X91704Y38643D01*
X91973Y38695D01*
X92241Y38592D01*
X92433Y38333D01*
G01X94038Y36215D02*
X94268Y35853D01*
X94574Y35647D01*
X94919Y35595D01*
X95226Y35647D01*
X95533Y35905D01*
X95724Y36215D01*
X95763Y36525D01*
X95686Y36887D01*
X95418Y37145D01*
X95149Y37248D01*
X94804D01*
G01X95149D02*
X95379Y37403D01*
X95571Y37662D01*
X95648Y37972D01*
X95571Y38282D01*
X95379Y38540D01*
X95034Y38695D01*
X94689Y38643D01*
X94344Y38437D01*
G01X89023Y56874D02*
Y59974D01*
X89982D01*
X90288Y59819D01*
X90480Y59612D01*
X90557Y59199D01*
X90480Y58786D01*
X90250Y58527D01*
X89982Y58372D01*
X89023D01*
G01X89982D02*
X90557Y56874D01*
G01X92890D02*
Y59974D01*
X92430Y59354D01*
G01Y56874D02*
X93350D01*
G01X95147Y57494D02*
X95377Y57132D01*
X95683Y56926D01*
X96028Y56874D01*
X96335Y56926D01*
X96642Y57184D01*
X96833Y57494D01*
X96872Y57804D01*
X96795Y58166D01*
X96527Y58424D01*
X96258Y58527D01*
X95913D01*
G01X96258D02*
X96488Y58682D01*
X96680Y58941D01*
X96757Y59251D01*
X96680Y59561D01*
X96488Y59819D01*
X96143Y59974D01*
X95798Y59922D01*
X95453Y59716D01*
G01X99550Y56874D02*
Y59974D01*
X98132Y57752D01*
X100048D01*
G01X95788Y76606D02*
Y79706D01*
X96747D01*
X97053Y79551D01*
X97245Y79344D01*
X97322Y78931D01*
X97245Y78518D01*
X97015Y78259D01*
X96747Y78104D01*
X95788D01*
G01X96747D02*
X97322Y76606D01*
G01X98812Y77071D02*
X99042Y76813D01*
X99310Y76658D01*
X99655Y76606D01*
X100000Y76709D01*
X100268Y76916D01*
X100460Y77278D01*
X100498Y77691D01*
X100422Y78104D01*
X100230Y78363D01*
X99962Y78569D01*
X99693Y78621D01*
X99425Y78569D01*
X99080Y78363D01*
X99195Y79706D01*
X100230D01*
G01X79224Y147591D02*
Y150691D01*
G01X80834D02*
Y147591D01*
G01Y149141D02*
X79224D01*
G01X83129Y147591D02*
Y150691D01*
X82669Y150071D01*
G01Y147591D02*
X83589D01*
G01X86229D02*
Y150691D01*
X85769Y150071D01*
G01Y147591D02*
X86689D01*
G01X87855Y247225D02*
X87605Y247478D01*
X87189Y247668D01*
X86605Y247795D01*
X86105Y247668D01*
X85772Y247415D01*
X85522Y246971D01*
Y245261D01*
X90522D01*
Y247351D01*
X90189Y247795D01*
X89689Y248048D01*
X89105Y248175D01*
X88522Y248048D01*
X88022Y247668D01*
X87855Y247225D01*
Y245261D01*
G01X90522Y252958D02*
X87189D01*
G01X87772D02*
X87439Y252705D01*
X87272Y252325D01*
X87189Y251881D01*
X87355Y251438D01*
X87689Y251058D01*
X88189Y250805D01*
X88855Y250678D01*
X89522Y250805D01*
X90022Y251058D01*
X90355Y251438D01*
X90522Y251881D01*
X90439Y252325D01*
X90189Y252705D01*
X89855Y252958D01*
G01X90522Y256031D02*
X87189D01*
G01X87855D02*
X87522Y256348D01*
X87272Y256665D01*
X87189Y257108D01*
X87272Y257425D01*
X87522Y257805D01*
G01X87605Y263031D02*
X87272Y262588D01*
X87189Y262208D01*
X87355Y261701D01*
X87689Y261321D01*
X88272Y261068D01*
X88855Y261005D01*
X89439Y261068D01*
X89939Y261321D01*
X90355Y261701D01*
X90522Y262208D01*
X90355Y262651D01*
X90022Y263031D01*
G01X90522Y267118D02*
X90439Y266738D01*
X90105Y266358D01*
X89522Y266105D01*
X88855Y265978D01*
X88189Y266105D01*
X87605Y266358D01*
X87272Y266738D01*
X87189Y267118D01*
X87272Y267498D01*
X87605Y267878D01*
X88189Y268131D01*
X88855Y268195D01*
X89522Y268131D01*
X90105Y267878D01*
X90439Y267498D01*
X90522Y267118D01*
G01X85522Y273358D02*
X90522D01*
G01X89772D02*
X90189Y273105D01*
X90439Y272725D01*
X90522Y272281D01*
X90355Y271775D01*
X89939Y271395D01*
X89439Y271141D01*
X88855Y271078D01*
X88272Y271141D01*
X87772Y271395D01*
X87355Y271775D01*
X87189Y272281D01*
X87272Y272725D01*
X87439Y273041D01*
X87772Y273358D01*
G01X88272Y276368D02*
Y278395D01*
X87689Y278205D01*
X87355Y277888D01*
X87189Y277445D01*
X87272Y277001D01*
X87522Y276621D01*
X88105Y276368D01*
X88605Y276241D01*
X89105D01*
X89605Y276368D01*
X90105Y276685D01*
X90439Y277065D01*
X90522Y277508D01*
X90355Y277951D01*
X89855Y278395D01*
G01X86412Y370812D02*
Y373912D01*
X87371D01*
X87677Y373757D01*
X87869Y373550D01*
X87946Y373137D01*
X87869Y372724D01*
X87639Y372465D01*
X87371Y372310D01*
X86412D01*
G01X87371D02*
X87946Y370812D01*
G01X89551Y372104D02*
X89819Y372465D01*
X90049Y372672D01*
X90356Y372775D01*
X90624Y372672D01*
X90816Y372465D01*
X90969Y372155D01*
X91007Y371794D01*
X90969Y371484D01*
X90816Y371174D01*
X90586Y370915D01*
X90317Y370812D01*
X90011Y370915D01*
X89742Y371225D01*
X89589Y371690D01*
X89551Y372207D01*
X89627Y372879D01*
X89742Y373240D01*
X89934Y373602D01*
X90202Y373860D01*
X90471Y373912D01*
X90739Y373809D01*
X90931Y373550D01*
G01X92727Y371174D02*
X92996Y370915D01*
X93302Y370812D01*
X93609Y370915D01*
X93877Y371225D01*
X94069Y371690D01*
X94146Y372155D01*
Y372724D01*
X94069Y373189D01*
X93877Y373602D01*
X93647Y373809D01*
X93379Y373912D01*
X93072Y373809D01*
X92842Y373602D01*
X92689Y373292D01*
X92612Y372879D01*
X92689Y372517D01*
X92881Y372155D01*
X93111Y371949D01*
X93379Y371897D01*
X93686Y372000D01*
X93916Y372259D01*
X94146Y372724D01*
G01X86412Y390123D02*
Y393223D01*
X87371D01*
X87677Y393068D01*
X87869Y392861D01*
X87946Y392448D01*
X87869Y392035D01*
X87639Y391776D01*
X87371Y391621D01*
X86412D01*
G01X87371D02*
X87946Y390123D01*
G01X90739D02*
Y393223D01*
X89321Y391001D01*
X91237D01*
G01X92651Y391415D02*
X92919Y391776D01*
X93149Y391983D01*
X93456Y392086D01*
X93724Y391983D01*
X93916Y391776D01*
X94069Y391466D01*
X94107Y391105D01*
X94069Y390795D01*
X93916Y390485D01*
X93686Y390226D01*
X93417Y390123D01*
X93111Y390226D01*
X92842Y390536D01*
X92689Y391001D01*
X92651Y391518D01*
X92727Y392190D01*
X92842Y392551D01*
X93034Y392913D01*
X93302Y393171D01*
X93571Y393223D01*
X93839Y393120D01*
X94031Y392861D01*
G01X86412Y375483D02*
Y378583D01*
X87371D01*
X87677Y378428D01*
X87869Y378221D01*
X87946Y377808D01*
X87869Y377395D01*
X87639Y377136D01*
X87371Y376981D01*
X86412D01*
G01X87371D02*
X87946Y375483D01*
G01X90739D02*
Y378583D01*
X89321Y376361D01*
X91237D01*
G01X93302Y375483D02*
X93379Y376155D01*
X93494Y376723D01*
X93647Y377240D01*
X93839Y377808D01*
X94146Y378583D01*
X92612D01*
G01X86412Y385138D02*
Y388238D01*
X87371D01*
X87677Y388083D01*
X87869Y387876D01*
X87946Y387463D01*
X87869Y387050D01*
X87639Y386791D01*
X87371Y386636D01*
X86412D01*
G01X87371D02*
X87946Y385138D01*
G01X89551Y386430D02*
X89819Y386791D01*
X90049Y386998D01*
X90356Y387101D01*
X90624Y386998D01*
X90816Y386791D01*
X90969Y386481D01*
X91007Y386120D01*
X90969Y385810D01*
X90816Y385500D01*
X90586Y385241D01*
X90317Y385138D01*
X90011Y385241D01*
X89742Y385551D01*
X89589Y386016D01*
X89551Y386533D01*
X89627Y387205D01*
X89742Y387566D01*
X89934Y387928D01*
X90202Y388186D01*
X90471Y388238D01*
X90739Y388135D01*
X90931Y387876D01*
G01X92651Y386430D02*
X92919Y386791D01*
X93149Y386998D01*
X93456Y387101D01*
X93724Y386998D01*
X93916Y386791D01*
X94069Y386481D01*
X94107Y386120D01*
X94069Y385810D01*
X93916Y385500D01*
X93686Y385241D01*
X93417Y385138D01*
X93111Y385241D01*
X92842Y385551D01*
X92689Y386016D01*
X92651Y386533D01*
X92727Y387205D01*
X92842Y387566D01*
X93034Y387928D01*
X93302Y388186D01*
X93571Y388238D01*
X93839Y388135D01*
X94031Y387876D01*
G01X86412Y380289D02*
Y383389D01*
X87371D01*
X87677Y383234D01*
X87869Y383027D01*
X87946Y382614D01*
X87869Y382201D01*
X87639Y381942D01*
X87371Y381787D01*
X86412D01*
G01X87371D02*
X87946Y380289D01*
G01X89551Y381581D02*
X89819Y381942D01*
X90049Y382149D01*
X90356Y382252D01*
X90624Y382149D01*
X90816Y381942D01*
X90969Y381632D01*
X91007Y381271D01*
X90969Y380961D01*
X90816Y380651D01*
X90586Y380392D01*
X90317Y380289D01*
X90011Y380392D01*
X89742Y380702D01*
X89589Y381167D01*
X89551Y381684D01*
X89627Y382356D01*
X89742Y382717D01*
X89934Y383079D01*
X90202Y383337D01*
X90471Y383389D01*
X90739Y383286D01*
X90931Y383027D01*
G01X93379Y380289D02*
X93647Y380341D01*
X93954Y380496D01*
X94146Y380754D01*
X94222Y381116D01*
X94146Y381477D01*
X93916Y381787D01*
X93571Y381942D01*
X93187D01*
X92957Y382046D01*
X92766Y382304D01*
X92689Y382666D01*
X92804Y383027D01*
X93072Y383286D01*
X93379Y383389D01*
X93686Y383286D01*
X93954Y383027D01*
X94069Y382666D01*
X93992Y382304D01*
X93801Y382046D01*
X93571Y381942D01*
X93187D01*
X92842Y381787D01*
X92612Y381477D01*
X92536Y381116D01*
X92612Y380754D01*
X92804Y380496D01*
X93111Y380341D01*
X93379Y380289D01*
G01X86412Y394927D02*
Y398027D01*
X87371D01*
X87677Y397872D01*
X87869Y397665D01*
X87946Y397252D01*
X87869Y396839D01*
X87639Y396580D01*
X87371Y396425D01*
X86412D01*
G01X87371D02*
X87946Y394927D01*
G01X89551Y396219D02*
X89819Y396580D01*
X90049Y396787D01*
X90356Y396890D01*
X90624Y396787D01*
X90816Y396580D01*
X90969Y396270D01*
X91007Y395909D01*
X90969Y395599D01*
X90816Y395289D01*
X90586Y395030D01*
X90317Y394927D01*
X90011Y395030D01*
X89742Y395340D01*
X89589Y395805D01*
X89551Y396322D01*
X89627Y396994D01*
X89742Y397355D01*
X89934Y397717D01*
X90202Y397975D01*
X90471Y398027D01*
X90739Y397924D01*
X90931Y397665D01*
G01X93302Y394927D02*
X93379Y395599D01*
X93494Y396167D01*
X93647Y396684D01*
X93839Y397252D01*
X94146Y398027D01*
X92612D01*
G01X86280Y399160D02*
Y402260D01*
X87239D01*
X87545Y402105D01*
X87737Y401898D01*
X87814Y401485D01*
X87737Y401072D01*
X87507Y400813D01*
X87239Y400658D01*
X86280D01*
G01X87239D02*
X87814Y399160D01*
G01X90147D02*
Y402260D01*
X89687Y401640D01*
G01Y399160D02*
X90607D01*
G01X92404Y399780D02*
X92634Y399418D01*
X92940Y399212D01*
X93285Y399160D01*
X93592Y399212D01*
X93899Y399470D01*
X94090Y399780D01*
X94129Y400090D01*
X94052Y400452D01*
X93784Y400710D01*
X93515Y400813D01*
X93170D01*
G01X93515D02*
X93745Y400968D01*
X93937Y401227D01*
X94014Y401537D01*
X93937Y401847D01*
X93745Y402105D01*
X93400Y402260D01*
X93055Y402208D01*
X92710Y402002D01*
G01X95504Y399625D02*
X95734Y399367D01*
X96002Y399212D01*
X96347Y399160D01*
X96692Y399263D01*
X96960Y399470D01*
X97152Y399832D01*
X97190Y400245D01*
X97114Y400658D01*
X96922Y400917D01*
X96654Y401123D01*
X96385Y401175D01*
X96117Y401123D01*
X95772Y400917D01*
X95887Y402260D01*
X96922D01*
G01X95996Y424681D02*
Y427781D01*
X96955D01*
X97261Y427626D01*
X97453Y427419D01*
X97530Y427006D01*
X97453Y426593D01*
X97223Y426334D01*
X96955Y426179D01*
X95996D01*
G01X96955D02*
X97530Y424681D01*
G01X99786D02*
X99863Y425353D01*
X99978Y425921D01*
X100131Y426438D01*
X100323Y427006D01*
X100630Y427781D01*
X99096D01*
G01X80972Y600696D02*
X75972D01*
Y602280D01*
X76222Y602786D01*
X76555Y603103D01*
X77222Y603230D01*
X77889Y603103D01*
X78305Y602723D01*
X78555Y602280D01*
Y600696D01*
G01Y602280D02*
X80972Y603230D01*
G01X78722Y606113D02*
Y608140D01*
X78139Y607950D01*
X77805Y607633D01*
X77639Y607190D01*
X77722Y606746D01*
X77972Y606366D01*
X78555Y606113D01*
X79055Y605986D01*
X79555D01*
X80055Y606113D01*
X80555Y606430D01*
X80889Y606810D01*
X80972Y607253D01*
X80805Y607696D01*
X80305Y608140D01*
G01X77639Y611023D02*
X80972Y612163D01*
X77639Y613303D01*
G01X81139Y617263D02*
X81055Y617136D01*
X80889D01*
X80805Y617263D01*
X80889Y617390D01*
X81055D01*
X81139Y617263D01*
G01X78889D02*
X78805Y617136D01*
X78639D01*
X78555Y617263D01*
X78639Y617390D01*
X78805D01*
X78889Y617263D01*
G01X80972Y620780D02*
X75972Y622363D01*
X80972Y623946D01*
G01X79222Y623376D02*
Y621350D01*
G01X88180Y693110D02*
Y673310D01*
X76980D01*
Y693110D01*
X80780D01*
X82580Y691310D01*
X84380Y693110D01*
X88180D01*
G01X79363Y710796D02*
X89563D01*
Y706196D01*
X79363D01*
Y710796D01*
G01X84463D02*
Y706196D01*
G01X90281Y703118D02*
Y696918D01*
X87081D01*
Y703118D01*
X90281D01*
G01X76909Y696128D02*
X73809D01*
Y697087D01*
X73964Y697393D01*
X74171Y697585D01*
X74584Y697662D01*
X74997Y697585D01*
X75256Y697355D01*
X75411Y697087D01*
Y696128D01*
G01Y697087D02*
X76909Y697662D01*
G01Y699995D02*
X73809D01*
X74429Y699535D01*
G01X76909D02*
Y700455D01*
G01X75617Y702367D02*
X75256Y702635D01*
X75049Y702865D01*
X74946Y703172D01*
X75049Y703440D01*
X75256Y703632D01*
X75566Y703785D01*
X75927Y703823D01*
X76237Y703785D01*
X76547Y703632D01*
X76806Y703402D01*
X76909Y703133D01*
X76806Y702827D01*
X76496Y702558D01*
X76031Y702405D01*
X75514Y702367D01*
X74842Y702443D01*
X74481Y702558D01*
X74119Y702750D01*
X73861Y703018D01*
X73809Y703287D01*
X73912Y703555D01*
X74171Y703747D01*
G01X76909Y706195D02*
X73809D01*
X74429Y705735D01*
G01X76909D02*
Y706655D01*
G01X91260Y696918D02*
Y703118D01*
X94460D01*
Y696918D01*
X91260D01*
G01X81869Y703118D02*
Y696918D01*
X78669D01*
Y703118D01*
X81869D01*
G01X82933Y696918D02*
Y703118D01*
X86133D01*
Y696918D01*
X82933D01*
G01X80080Y690710D02*
G03I-1000J0D01*
G01X77552Y715131D02*
X77322Y715286D01*
X77054Y715389D01*
X76747D01*
X76402Y715234D01*
X76134Y714976D01*
X75942Y714666D01*
X75789Y714149D01*
X75751Y713684D01*
X75827Y713219D01*
X75942Y712909D01*
X76172Y712599D01*
X76441Y712392D01*
X76709Y712289D01*
X76977D01*
X77246Y712392D01*
X77476Y712547D01*
X77667Y712754D01*
G01X79157Y712651D02*
X79426Y712392D01*
X79732Y712289D01*
X80039Y712392D01*
X80307Y712702D01*
X80499Y713167D01*
X80576Y713632D01*
Y714201D01*
X80499Y714666D01*
X80307Y715079D01*
X80077Y715286D01*
X79809Y715389D01*
X79502Y715286D01*
X79272Y715079D01*
X79119Y714769D01*
X79042Y714356D01*
X79119Y713994D01*
X79311Y713632D01*
X79541Y713426D01*
X79809Y713374D01*
X80116Y713477D01*
X80346Y713736D01*
X80576Y714201D01*
G01X82181Y714872D02*
X82411Y715182D01*
X82679Y715337D01*
X82986Y715389D01*
X83369Y715286D01*
X83637Y715027D01*
X83714Y714717D01*
X83676Y714407D01*
X83522Y714149D01*
X82756Y713632D01*
X82411Y713271D01*
X82181Y712754D01*
X82104Y712289D01*
X83714D01*
G01X87277Y718844D02*
Y721944D01*
X88236D01*
X88542Y721789D01*
X88734Y721582D01*
X88811Y721169D01*
X88734Y720756D01*
X88504Y720497D01*
X88236Y720342D01*
X87277D01*
G01X88236D02*
X88811Y718844D01*
G01X90301Y719309D02*
X90531Y719051D01*
X90799Y718896D01*
X91144Y718844D01*
X91489Y718947D01*
X91757Y719154D01*
X91949Y719516D01*
X91987Y719929D01*
X91911Y720342D01*
X91719Y720601D01*
X91451Y720807D01*
X91182Y720859D01*
X90914Y720807D01*
X90569Y720601D01*
X90684Y721944D01*
X91719D01*
G01X93401Y719309D02*
X93631Y719051D01*
X93899Y718896D01*
X94244Y718844D01*
X94589Y718947D01*
X94857Y719154D01*
X95049Y719516D01*
X95087Y719929D01*
X95011Y720342D01*
X94819Y720601D01*
X94551Y720807D01*
X94282Y720859D01*
X94014Y720807D01*
X93669Y720601D01*
X93784Y721944D01*
X94819D01*
G01X87277Y728497D02*
Y731597D01*
X88236D01*
X88542Y731442D01*
X88734Y731235D01*
X88811Y730822D01*
X88734Y730409D01*
X88504Y730150D01*
X88236Y729995D01*
X87277D01*
G01X88236D02*
X88811Y728497D01*
G01X91067D02*
X91144Y729169D01*
X91259Y729737D01*
X91412Y730254D01*
X91604Y730822D01*
X91911Y731597D01*
X90377D01*
G01X94244D02*
X93937Y731494D01*
X93707Y731235D01*
X93554Y730925D01*
X93439Y730512D01*
X93401Y730047D01*
X93439Y729582D01*
X93554Y729169D01*
X93707Y728859D01*
X93937Y728600D01*
X94244Y728497D01*
X94551Y728600D01*
X94781Y728859D01*
X94934Y729169D01*
X95049Y729582D01*
X95087Y730047D01*
X95049Y730512D01*
X94934Y730925D01*
X94781Y731235D01*
X94551Y731494D01*
X94244Y731597D01*
G01X87277Y723556D02*
Y726656D01*
X88236D01*
X88542Y726501D01*
X88734Y726294D01*
X88811Y725881D01*
X88734Y725468D01*
X88504Y725209D01*
X88236Y725054D01*
X87277D01*
G01X88236D02*
X88811Y723556D01*
G01X91067D02*
X91144Y724228D01*
X91259Y724796D01*
X91412Y725313D01*
X91604Y725881D01*
X91911Y726656D01*
X90377D01*
G01X93516Y726139D02*
X93746Y726449D01*
X94014Y726604D01*
X94321Y726656D01*
X94704Y726553D01*
X94972Y726294D01*
X95049Y725984D01*
X95011Y725674D01*
X94857Y725416D01*
X94091Y724899D01*
X93746Y724538D01*
X93516Y724021D01*
X93439Y723556D01*
X95049D01*
G01X87277Y714036D02*
Y717136D01*
X88236D01*
X88542Y716981D01*
X88734Y716774D01*
X88811Y716361D01*
X88734Y715948D01*
X88504Y715689D01*
X88236Y715534D01*
X87277D01*
G01X88236D02*
X88811Y714036D01*
G01X91067D02*
X91144Y714708D01*
X91259Y715276D01*
X91412Y715793D01*
X91604Y716361D01*
X91911Y717136D01*
X90377D01*
G01X93401Y714656D02*
X93631Y714294D01*
X93937Y714088D01*
X94282Y714036D01*
X94589Y714088D01*
X94896Y714346D01*
X95087Y714656D01*
X95126Y714966D01*
X95049Y715328D01*
X94781Y715586D01*
X94512Y715689D01*
X94167D01*
G01X94512D02*
X94742Y715844D01*
X94934Y716103D01*
X95011Y716413D01*
X94934Y716723D01*
X94742Y716981D01*
X94397Y717136D01*
X94052Y717084D01*
X93707Y716878D01*
G01X87246Y742490D02*
Y745590D01*
X88205D01*
X88511Y745435D01*
X88703Y745228D01*
X88780Y744815D01*
X88703Y744402D01*
X88473Y744143D01*
X88205Y743988D01*
X87246D01*
G01X88205D02*
X88780Y742490D01*
G01X90270Y742955D02*
X90500Y742697D01*
X90768Y742542D01*
X91113Y742490D01*
X91458Y742593D01*
X91726Y742800D01*
X91918Y743162D01*
X91956Y743575D01*
X91880Y743988D01*
X91688Y744247D01*
X91420Y744453D01*
X91151Y744505D01*
X90883Y744453D01*
X90538Y744247D01*
X90653Y745590D01*
X91688D01*
G01X94213Y742490D02*
Y745590D01*
X93753Y744970D01*
G01Y742490D02*
X94673D01*
G01X87277Y733347D02*
Y736447D01*
X88236D01*
X88542Y736292D01*
X88734Y736085D01*
X88811Y735672D01*
X88734Y735259D01*
X88504Y735000D01*
X88236Y734845D01*
X87277D01*
G01X88236D02*
X88811Y733347D01*
G01X91604D02*
Y736447D01*
X90186Y734225D01*
X92102D01*
G01X94244Y733347D02*
X94512Y733399D01*
X94819Y733554D01*
X95011Y733812D01*
X95087Y734174D01*
X95011Y734535D01*
X94781Y734845D01*
X94436Y735000D01*
X94052D01*
X93822Y735104D01*
X93631Y735362D01*
X93554Y735724D01*
X93669Y736085D01*
X93937Y736344D01*
X94244Y736447D01*
X94551Y736344D01*
X94819Y736085D01*
X94934Y735724D01*
X94857Y735362D01*
X94666Y735104D01*
X94436Y735000D01*
X94052D01*
X93707Y734845D01*
X93477Y734535D01*
X93401Y734174D01*
X93477Y733812D01*
X93669Y733554D01*
X93976Y733399D01*
X94244Y733347D01*
G01X87277Y738061D02*
Y741161D01*
X88236D01*
X88542Y741006D01*
X88734Y740799D01*
X88811Y740386D01*
X88734Y739973D01*
X88504Y739714D01*
X88236Y739559D01*
X87277D01*
G01X88236D02*
X88811Y738061D01*
G01X91067D02*
X91144Y738733D01*
X91259Y739301D01*
X91412Y739818D01*
X91604Y740386D01*
X91911Y741161D01*
X90377D01*
G01X94244Y738061D02*
Y741161D01*
X93784Y740541D01*
G01Y738061D02*
X94704D01*
G01X86720Y747030D02*
Y750130D01*
X87679D01*
X87985Y749975D01*
X88177Y749768D01*
X88254Y749355D01*
X88177Y748942D01*
X87947Y748683D01*
X87679Y748528D01*
X86720D01*
G01X87679D02*
X88254Y747030D01*
G01X90587D02*
Y750130D01*
X90127Y749510D01*
G01Y747030D02*
X91047D01*
G01X92844Y747650D02*
X93074Y747288D01*
X93380Y747082D01*
X93725Y747030D01*
X94032Y747082D01*
X94339Y747340D01*
X94530Y747650D01*
X94569Y747960D01*
X94492Y748322D01*
X94224Y748580D01*
X93955Y748683D01*
X93610D01*
G01X93955D02*
X94185Y748838D01*
X94377Y749097D01*
X94454Y749407D01*
X94377Y749717D01*
X94185Y749975D01*
X93840Y750130D01*
X93495Y750078D01*
X93150Y749872D01*
G01X96059Y748322D02*
X96327Y748683D01*
X96557Y748890D01*
X96864Y748993D01*
X97132Y748890D01*
X97324Y748683D01*
X97477Y748373D01*
X97515Y748012D01*
X97477Y747702D01*
X97324Y747392D01*
X97094Y747133D01*
X96825Y747030D01*
X96519Y747133D01*
X96250Y747443D01*
X96097Y747908D01*
X96059Y748425D01*
X96135Y749097D01*
X96250Y749458D01*
X96442Y749820D01*
X96710Y750078D01*
X96979Y750130D01*
X97247Y750027D01*
X97439Y749768D01*
G01X93892Y772296D02*
Y775396D01*
X94851D01*
X95157Y775241D01*
X95349Y775034D01*
X95426Y774621D01*
X95349Y774208D01*
X95119Y773949D01*
X94851Y773794D01*
X93892D01*
G01X94851D02*
X95426Y772296D01*
G01X97031Y773588D02*
X97299Y773949D01*
X97529Y774156D01*
X97836Y774259D01*
X98104Y774156D01*
X98296Y773949D01*
X98449Y773639D01*
X98487Y773278D01*
X98449Y772968D01*
X98296Y772658D01*
X98066Y772399D01*
X97797Y772296D01*
X97491Y772399D01*
X97222Y772709D01*
X97069Y773174D01*
X97031Y773691D01*
X97107Y774363D01*
X97222Y774724D01*
X97414Y775086D01*
X97682Y775344D01*
X97951Y775396D01*
X98219Y775293D01*
X98411Y775034D01*
G01X87250Y1070852D02*
Y1073952D01*
X88209D01*
X88515Y1073797D01*
X88707Y1073590D01*
X88784Y1073177D01*
X88707Y1072764D01*
X88477Y1072505D01*
X88209Y1072350D01*
X87250D01*
G01X88209D02*
X88784Y1070852D01*
G01X90274Y1071317D02*
X90504Y1071059D01*
X90772Y1070904D01*
X91117Y1070852D01*
X91462Y1070955D01*
X91730Y1071162D01*
X91922Y1071524D01*
X91960Y1071937D01*
X91884Y1072350D01*
X91692Y1072609D01*
X91424Y1072815D01*
X91155Y1072867D01*
X90887Y1072815D01*
X90542Y1072609D01*
X90657Y1073952D01*
X91692D01*
G01X94140Y1070852D02*
X94217Y1071524D01*
X94332Y1072092D01*
X94485Y1072609D01*
X94677Y1073177D01*
X94984Y1073952D01*
X93450D01*
G01X87250Y1066141D02*
Y1069241D01*
X88209D01*
X88515Y1069086D01*
X88707Y1068879D01*
X88784Y1068466D01*
X88707Y1068053D01*
X88477Y1067794D01*
X88209Y1067639D01*
X87250D01*
G01X88209D02*
X88784Y1066141D01*
G01X91040D02*
X91117Y1066813D01*
X91232Y1067381D01*
X91385Y1067898D01*
X91577Y1068466D01*
X91884Y1069241D01*
X90350D01*
G01X94140Y1066141D02*
X94217Y1066813D01*
X94332Y1067381D01*
X94485Y1067898D01*
X94677Y1068466D01*
X94984Y1069241D01*
X93450D01*
G01X88101Y1095430D02*
Y1098530D01*
X89060D01*
X89366Y1098375D01*
X89558Y1098168D01*
X89635Y1097755D01*
X89558Y1097342D01*
X89328Y1097083D01*
X89060Y1096928D01*
X88101D01*
G01X89060D02*
X89635Y1095430D01*
G01X91125Y1095895D02*
X91355Y1095637D01*
X91623Y1095482D01*
X91968Y1095430D01*
X92313Y1095533D01*
X92581Y1095740D01*
X92773Y1096102D01*
X92811Y1096515D01*
X92735Y1096928D01*
X92543Y1097187D01*
X92275Y1097393D01*
X92006Y1097445D01*
X91738Y1097393D01*
X91393Y1097187D01*
X91508Y1098530D01*
X92543D01*
G01X94340Y1098013D02*
X94570Y1098323D01*
X94838Y1098478D01*
X95145Y1098530D01*
X95528Y1098427D01*
X95796Y1098168D01*
X95873Y1097858D01*
X95835Y1097548D01*
X95681Y1097290D01*
X94915Y1096773D01*
X94570Y1096412D01*
X94340Y1095895D01*
X94263Y1095430D01*
X95873D01*
G01X87161Y1089853D02*
Y1092953D01*
X88120D01*
X88426Y1092798D01*
X88618Y1092591D01*
X88695Y1092178D01*
X88618Y1091765D01*
X88388Y1091506D01*
X88120Y1091351D01*
X87161D01*
G01X88120D02*
X88695Y1089853D01*
G01X90185Y1090318D02*
X90415Y1090060D01*
X90683Y1089905D01*
X91028Y1089853D01*
X91373Y1089956D01*
X91641Y1090163D01*
X91833Y1090525D01*
X91871Y1090938D01*
X91795Y1091351D01*
X91603Y1091610D01*
X91335Y1091816D01*
X91066Y1091868D01*
X90798Y1091816D01*
X90453Y1091610D01*
X90568Y1092953D01*
X91603D01*
G01X93400Y1091145D02*
X93668Y1091506D01*
X93898Y1091713D01*
X94205Y1091816D01*
X94473Y1091713D01*
X94665Y1091506D01*
X94818Y1091196D01*
X94856Y1090835D01*
X94818Y1090525D01*
X94665Y1090215D01*
X94435Y1089956D01*
X94166Y1089853D01*
X93860Y1089956D01*
X93591Y1090266D01*
X93438Y1090731D01*
X93400Y1091248D01*
X93476Y1091920D01*
X93591Y1092281D01*
X93783Y1092643D01*
X94051Y1092901D01*
X94320Y1092953D01*
X94588Y1092850D01*
X94780Y1092591D01*
G01X87250Y1080417D02*
Y1083517D01*
X88209D01*
X88515Y1083362D01*
X88707Y1083155D01*
X88784Y1082742D01*
X88707Y1082329D01*
X88477Y1082070D01*
X88209Y1081915D01*
X87250D01*
G01X88209D02*
X88784Y1080417D01*
G01X91040D02*
X91117Y1081089D01*
X91232Y1081657D01*
X91385Y1082174D01*
X91577Y1082742D01*
X91884Y1083517D01*
X90350D01*
G01X94677Y1080417D02*
Y1083517D01*
X93259Y1081295D01*
X95175D01*
G01X87250Y1075527D02*
Y1078627D01*
X88209D01*
X88515Y1078472D01*
X88707Y1078265D01*
X88784Y1077852D01*
X88707Y1077439D01*
X88477Y1077180D01*
X88209Y1077025D01*
X87250D01*
G01X88209D02*
X88784Y1075527D01*
G01X91040D02*
X91117Y1076199D01*
X91232Y1076767D01*
X91385Y1077284D01*
X91577Y1077852D01*
X91884Y1078627D01*
X90350D01*
G01X93489Y1076819D02*
X93757Y1077180D01*
X93987Y1077387D01*
X94294Y1077490D01*
X94562Y1077387D01*
X94754Y1077180D01*
X94907Y1076870D01*
X94945Y1076509D01*
X94907Y1076199D01*
X94754Y1075889D01*
X94524Y1075630D01*
X94255Y1075527D01*
X93949Y1075630D01*
X93680Y1075940D01*
X93527Y1076405D01*
X93489Y1076922D01*
X93565Y1077594D01*
X93680Y1077955D01*
X93872Y1078317D01*
X94140Y1078575D01*
X94409Y1078627D01*
X94677Y1078524D01*
X94869Y1078265D01*
G01X87250Y1085721D02*
Y1088821D01*
X88209D01*
X88515Y1088666D01*
X88707Y1088459D01*
X88784Y1088046D01*
X88707Y1087633D01*
X88477Y1087374D01*
X88209Y1087219D01*
X87250D01*
G01X88209D02*
X88784Y1085721D01*
G01X91040D02*
X91117Y1086393D01*
X91232Y1086961D01*
X91385Y1087478D01*
X91577Y1088046D01*
X91884Y1088821D01*
X90350D01*
G01X93374Y1086186D02*
X93604Y1085928D01*
X93872Y1085773D01*
X94217Y1085721D01*
X94562Y1085824D01*
X94830Y1086031D01*
X95022Y1086393D01*
X95060Y1086806D01*
X94984Y1087219D01*
X94792Y1087478D01*
X94524Y1087684D01*
X94255Y1087736D01*
X93987Y1087684D01*
X93642Y1087478D01*
X93757Y1088821D01*
X94792D01*
G01X92675Y1100448D02*
Y1103548D01*
X93634D01*
X93940Y1103393D01*
X94132Y1103186D01*
X94209Y1102773D01*
X94132Y1102360D01*
X93902Y1102101D01*
X93634Y1101946D01*
X92675D01*
G01X93634D02*
X94209Y1100448D01*
G01X96542D02*
Y1103548D01*
X96082Y1102928D01*
G01Y1100448D02*
X97002D01*
G01X98799Y1101068D02*
X99029Y1100706D01*
X99335Y1100500D01*
X99680Y1100448D01*
X99987Y1100500D01*
X100294Y1100758D01*
X100485Y1101068D01*
X100524Y1101378D01*
X100447Y1101740D01*
X100179Y1101998D01*
X99910Y1102101D01*
X99565D01*
G01X99910D02*
X100140Y1102256D01*
X100332Y1102515D01*
X100409Y1102825D01*
X100332Y1103135D01*
X100140Y1103393D01*
X99795Y1103548D01*
X99450Y1103496D01*
X99105Y1103290D01*
G01X102665Y1100448D02*
X102742Y1101120D01*
X102857Y1101688D01*
X103010Y1102205D01*
X103202Y1102773D01*
X103509Y1103548D01*
X101975D01*
G01X94184Y1120735D02*
Y1123835D01*
X95143D01*
X95449Y1123680D01*
X95641Y1123473D01*
X95718Y1123060D01*
X95641Y1122647D01*
X95411Y1122388D01*
X95143Y1122233D01*
X94184D01*
G01X95143D02*
X95718Y1120735D01*
G01X97323Y1123318D02*
X97553Y1123628D01*
X97821Y1123783D01*
X98128Y1123835D01*
X98511Y1123732D01*
X98779Y1123473D01*
X98856Y1123163D01*
X98818Y1122853D01*
X98664Y1122595D01*
X97898Y1122078D01*
X97553Y1121717D01*
X97323Y1121200D01*
X97246Y1120735D01*
X98856D01*
G01X101151Y1123835D02*
X100844Y1123732D01*
X100614Y1123473D01*
X100461Y1123163D01*
X100346Y1122750D01*
X100308Y1122285D01*
X100346Y1121820D01*
X100461Y1121407D01*
X100614Y1121097D01*
X100844Y1120838D01*
X101151Y1120735D01*
X101458Y1120838D01*
X101688Y1121097D01*
X101841Y1121407D01*
X101956Y1121820D01*
X101994Y1122285D01*
X101956Y1122750D01*
X101841Y1123163D01*
X101688Y1123473D01*
X101458Y1123732D01*
X101151Y1123835D01*
G01X86762Y1418984D02*
Y1422084D01*
X87721D01*
X88027Y1421929D01*
X88219Y1421722D01*
X88296Y1421309D01*
X88219Y1420896D01*
X87989Y1420637D01*
X87721Y1420482D01*
X86762D01*
G01X87721D02*
X88296Y1418984D01*
G01X89786Y1419449D02*
X90016Y1419191D01*
X90284Y1419036D01*
X90629Y1418984D01*
X90974Y1419087D01*
X91242Y1419294D01*
X91434Y1419656D01*
X91472Y1420069D01*
X91396Y1420482D01*
X91204Y1420741D01*
X90936Y1420947D01*
X90667Y1420999D01*
X90399Y1420947D01*
X90054Y1420741D01*
X90169Y1422084D01*
X91204D01*
G01X93077Y1419346D02*
X93346Y1419087D01*
X93652Y1418984D01*
X93959Y1419087D01*
X94227Y1419397D01*
X94419Y1419862D01*
X94496Y1420327D01*
Y1420896D01*
X94419Y1421361D01*
X94227Y1421774D01*
X93997Y1421981D01*
X93729Y1422084D01*
X93422Y1421981D01*
X93192Y1421774D01*
X93039Y1421464D01*
X92962Y1421051D01*
X93039Y1420689D01*
X93231Y1420327D01*
X93461Y1420121D01*
X93729Y1420069D01*
X94036Y1420172D01*
X94266Y1420431D01*
X94496Y1420896D01*
G01X86762Y1433533D02*
Y1436633D01*
X87721D01*
X88027Y1436478D01*
X88219Y1436271D01*
X88296Y1435858D01*
X88219Y1435445D01*
X87989Y1435186D01*
X87721Y1435031D01*
X86762D01*
G01X87721D02*
X88296Y1433533D01*
G01X90552D02*
X90629Y1434205D01*
X90744Y1434773D01*
X90897Y1435290D01*
X91089Y1435858D01*
X91396Y1436633D01*
X89862D01*
G01X93729Y1433533D02*
X93997Y1433585D01*
X94304Y1433740D01*
X94496Y1433998D01*
X94572Y1434360D01*
X94496Y1434721D01*
X94266Y1435031D01*
X93921Y1435186D01*
X93537D01*
X93307Y1435290D01*
X93116Y1435548D01*
X93039Y1435910D01*
X93154Y1436271D01*
X93422Y1436530D01*
X93729Y1436633D01*
X94036Y1436530D01*
X94304Y1436271D01*
X94419Y1435910D01*
X94342Y1435548D01*
X94151Y1435290D01*
X93921Y1435186D01*
X93537D01*
X93192Y1435031D01*
X92962Y1434721D01*
X92886Y1434360D01*
X92962Y1433998D01*
X93154Y1433740D01*
X93461Y1433585D01*
X93729Y1433533D01*
G01X86762Y1428687D02*
Y1431787D01*
X87721D01*
X88027Y1431632D01*
X88219Y1431425D01*
X88296Y1431012D01*
X88219Y1430599D01*
X87989Y1430340D01*
X87721Y1430185D01*
X86762D01*
G01X87721D02*
X88296Y1428687D01*
G01X90629D02*
X90897Y1428739D01*
X91204Y1428894D01*
X91396Y1429152D01*
X91472Y1429514D01*
X91396Y1429875D01*
X91166Y1430185D01*
X90821Y1430340D01*
X90437D01*
X90207Y1430444D01*
X90016Y1430702D01*
X89939Y1431064D01*
X90054Y1431425D01*
X90322Y1431684D01*
X90629Y1431787D01*
X90936Y1431684D01*
X91204Y1431425D01*
X91319Y1431064D01*
X91242Y1430702D01*
X91051Y1430444D01*
X90821Y1430340D01*
X90437D01*
X90092Y1430185D01*
X89862Y1429875D01*
X89786Y1429514D01*
X89862Y1429152D01*
X90054Y1428894D01*
X90361Y1428739D01*
X90629Y1428687D01*
G01X93729Y1431787D02*
X93422Y1431684D01*
X93192Y1431425D01*
X93039Y1431115D01*
X92924Y1430702D01*
X92886Y1430237D01*
X92924Y1429772D01*
X93039Y1429359D01*
X93192Y1429049D01*
X93422Y1428790D01*
X93729Y1428687D01*
X94036Y1428790D01*
X94266Y1429049D01*
X94419Y1429359D01*
X94534Y1429772D01*
X94572Y1430237D01*
X94534Y1430702D01*
X94419Y1431115D01*
X94266Y1431425D01*
X94036Y1431684D01*
X93729Y1431787D01*
G01X86762Y1423832D02*
Y1426932D01*
X87721D01*
X88027Y1426777D01*
X88219Y1426570D01*
X88296Y1426157D01*
X88219Y1425744D01*
X87989Y1425485D01*
X87721Y1425330D01*
X86762D01*
G01X87721D02*
X88296Y1423832D01*
G01X90629D02*
X90897Y1423884D01*
X91204Y1424039D01*
X91396Y1424297D01*
X91472Y1424659D01*
X91396Y1425020D01*
X91166Y1425330D01*
X90821Y1425485D01*
X90437D01*
X90207Y1425589D01*
X90016Y1425847D01*
X89939Y1426209D01*
X90054Y1426570D01*
X90322Y1426829D01*
X90629Y1426932D01*
X90936Y1426829D01*
X91204Y1426570D01*
X91319Y1426209D01*
X91242Y1425847D01*
X91051Y1425589D01*
X90821Y1425485D01*
X90437D01*
X90092Y1425330D01*
X89862Y1425020D01*
X89786Y1424659D01*
X89862Y1424297D01*
X90054Y1424039D01*
X90361Y1423884D01*
X90629Y1423832D01*
G01X93729D02*
Y1426932D01*
X93269Y1426312D01*
G01Y1423832D02*
X94189D01*
G01X87069Y1448040D02*
Y1451140D01*
X88028D01*
X88334Y1450985D01*
X88526Y1450778D01*
X88603Y1450365D01*
X88526Y1449952D01*
X88296Y1449693D01*
X88028Y1449538D01*
X87069D01*
G01X88028D02*
X88603Y1448040D01*
G01X90093Y1448505D02*
X90323Y1448247D01*
X90591Y1448092D01*
X90936Y1448040D01*
X91281Y1448143D01*
X91549Y1448350D01*
X91741Y1448712D01*
X91779Y1449125D01*
X91703Y1449538D01*
X91511Y1449797D01*
X91243Y1450003D01*
X90974Y1450055D01*
X90706Y1450003D01*
X90361Y1449797D01*
X90476Y1451140D01*
X91511D01*
G01X93193Y1448660D02*
X93423Y1448298D01*
X93729Y1448092D01*
X94074Y1448040D01*
X94381Y1448092D01*
X94688Y1448350D01*
X94879Y1448660D01*
X94918Y1448970D01*
X94841Y1449332D01*
X94573Y1449590D01*
X94304Y1449693D01*
X93959D01*
G01X94304D02*
X94534Y1449848D01*
X94726Y1450107D01*
X94803Y1450417D01*
X94726Y1450727D01*
X94534Y1450985D01*
X94189Y1451140D01*
X93844Y1451088D01*
X93499Y1450882D01*
G01X86762Y1443235D02*
Y1446335D01*
X87721D01*
X88027Y1446180D01*
X88219Y1445973D01*
X88296Y1445560D01*
X88219Y1445147D01*
X87989Y1444888D01*
X87721Y1444733D01*
X86762D01*
G01X87721D02*
X88296Y1443235D01*
G01X89786Y1443700D02*
X90016Y1443442D01*
X90284Y1443287D01*
X90629Y1443235D01*
X90974Y1443338D01*
X91242Y1443545D01*
X91434Y1443907D01*
X91472Y1444320D01*
X91396Y1444733D01*
X91204Y1444992D01*
X90936Y1445198D01*
X90667Y1445250D01*
X90399Y1445198D01*
X90054Y1444992D01*
X90169Y1446335D01*
X91204D01*
G01X93729Y1443235D02*
X93997Y1443287D01*
X94304Y1443442D01*
X94496Y1443700D01*
X94572Y1444062D01*
X94496Y1444423D01*
X94266Y1444733D01*
X93921Y1444888D01*
X93537D01*
X93307Y1444992D01*
X93116Y1445250D01*
X93039Y1445612D01*
X93154Y1445973D01*
X93422Y1446232D01*
X93729Y1446335D01*
X94036Y1446232D01*
X94304Y1445973D01*
X94419Y1445612D01*
X94342Y1445250D01*
X94151Y1444992D01*
X93921Y1444888D01*
X93537D01*
X93192Y1444733D01*
X92962Y1444423D01*
X92886Y1444062D01*
X92962Y1443700D01*
X93154Y1443442D01*
X93461Y1443287D01*
X93729Y1443235D01*
G01X86762Y1438472D02*
Y1441572D01*
X87721D01*
X88027Y1441417D01*
X88219Y1441210D01*
X88296Y1440797D01*
X88219Y1440384D01*
X87989Y1440125D01*
X87721Y1439970D01*
X86762D01*
G01X87721D02*
X88296Y1438472D01*
G01X90552D02*
X90629Y1439144D01*
X90744Y1439712D01*
X90897Y1440229D01*
X91089Y1440797D01*
X91396Y1441572D01*
X89862D01*
G01X93077Y1438834D02*
X93346Y1438575D01*
X93652Y1438472D01*
X93959Y1438575D01*
X94227Y1438885D01*
X94419Y1439350D01*
X94496Y1439815D01*
Y1440384D01*
X94419Y1440849D01*
X94227Y1441262D01*
X93997Y1441469D01*
X93729Y1441572D01*
X93422Y1441469D01*
X93192Y1441262D01*
X93039Y1440952D01*
X92962Y1440539D01*
X93039Y1440177D01*
X93231Y1439815D01*
X93461Y1439609D01*
X93729Y1439557D01*
X94036Y1439660D01*
X94266Y1439919D01*
X94496Y1440384D01*
G01X86674Y1454224D02*
Y1457324D01*
X87633D01*
X87939Y1457169D01*
X88131Y1456962D01*
X88208Y1456549D01*
X88131Y1456136D01*
X87901Y1455877D01*
X87633Y1455722D01*
X86674D01*
G01X87633D02*
X88208Y1454224D01*
G01X90541D02*
Y1457324D01*
X90081Y1456704D01*
G01Y1454224D02*
X91001D01*
G01X92798Y1454844D02*
X93028Y1454482D01*
X93334Y1454276D01*
X93679Y1454224D01*
X93986Y1454276D01*
X94293Y1454534D01*
X94484Y1454844D01*
X94523Y1455154D01*
X94446Y1455516D01*
X94178Y1455774D01*
X93909Y1455877D01*
X93564D01*
G01X93909D02*
X94139Y1456032D01*
X94331Y1456291D01*
X94408Y1456601D01*
X94331Y1456911D01*
X94139Y1457169D01*
X93794Y1457324D01*
X93449Y1457272D01*
X93104Y1457066D01*
G01X96741Y1454224D02*
X97009Y1454276D01*
X97316Y1454431D01*
X97508Y1454689D01*
X97584Y1455051D01*
X97508Y1455412D01*
X97278Y1455722D01*
X96933Y1455877D01*
X96549D01*
X96319Y1455981D01*
X96128Y1456239D01*
X96051Y1456601D01*
X96166Y1456962D01*
X96434Y1457221D01*
X96741Y1457324D01*
X97048Y1457221D01*
X97316Y1456962D01*
X97431Y1456601D01*
X97354Y1456239D01*
X97163Y1455981D01*
X96933Y1455877D01*
X96549D01*
X96204Y1455722D01*
X95974Y1455412D01*
X95898Y1455051D01*
X95974Y1454689D01*
X96166Y1454431D01*
X96473Y1454276D01*
X96741Y1454224D01*
G01X94762Y1468226D02*
Y1471326D01*
X95721D01*
X96027Y1471171D01*
X96219Y1470964D01*
X96296Y1470551D01*
X96219Y1470138D01*
X95989Y1469879D01*
X95721Y1469724D01*
X94762D01*
G01X95721D02*
X96296Y1468226D01*
G01X98629D02*
Y1471326D01*
X98169Y1470706D01*
G01Y1468226D02*
X99089D01*
G01X101077Y1468588D02*
X101346Y1468329D01*
X101652Y1468226D01*
X101959Y1468329D01*
X102227Y1468639D01*
X102419Y1469104D01*
X102496Y1469569D01*
Y1470138D01*
X102419Y1470603D01*
X102227Y1471016D01*
X101997Y1471223D01*
X101729Y1471326D01*
X101422Y1471223D01*
X101192Y1471016D01*
X101039Y1470706D01*
X100962Y1470293D01*
X101039Y1469931D01*
X101231Y1469569D01*
X101461Y1469363D01*
X101729Y1469311D01*
X102036Y1469414D01*
X102266Y1469673D01*
X102496Y1470138D01*
G01X76594Y1618722D02*
X76904Y1618914D01*
X77111Y1619144D01*
X77214Y1619412D01*
X77111Y1619719D01*
X76904Y1619949D01*
X76594Y1620179D01*
X76181Y1620256D01*
X74114D01*
G01X74631Y1621861D02*
X74321Y1622091D01*
X74166Y1622359D01*
X74114Y1622666D01*
X74217Y1623049D01*
X74476Y1623317D01*
X74786Y1623394D01*
X75096Y1623356D01*
X75354Y1623202D01*
X75871Y1622436D01*
X76232Y1622091D01*
X76749Y1621861D01*
X77214Y1621784D01*
Y1623394D01*
G01Y1625689D02*
X77162Y1625957D01*
X77007Y1626264D01*
X76749Y1626456D01*
X76387Y1626532D01*
X76026Y1626456D01*
X75716Y1626226D01*
X75561Y1625881D01*
Y1625497D01*
X75457Y1625267D01*
X75199Y1625076D01*
X74837Y1624999D01*
X74476Y1625114D01*
X74217Y1625382D01*
X74114Y1625689D01*
X74217Y1625996D01*
X74476Y1626264D01*
X74837Y1626379D01*
X75199Y1626302D01*
X75457Y1626111D01*
X75561Y1625881D01*
Y1625497D01*
X75716Y1625152D01*
X76026Y1624922D01*
X76387Y1624846D01*
X76749Y1624922D01*
X77007Y1625114D01*
X77162Y1625421D01*
X77214Y1625689D01*
G01X91505Y1723022D02*
X88405D01*
Y1723981D01*
X88560Y1724287D01*
X88767Y1724479D01*
X89180Y1724556D01*
X89593Y1724479D01*
X89852Y1724249D01*
X90007Y1723981D01*
Y1723022D01*
G01Y1723981D02*
X91505Y1724556D01*
G01Y1726889D02*
X88405D01*
X89025Y1726429D01*
G01X91505D02*
Y1727349D01*
G01X91040Y1729146D02*
X91298Y1729376D01*
X91453Y1729644D01*
X91505Y1729989D01*
X91402Y1730334D01*
X91195Y1730602D01*
X90833Y1730794D01*
X90420Y1730832D01*
X90007Y1730756D01*
X89748Y1730564D01*
X89542Y1730296D01*
X89490Y1730027D01*
X89542Y1729759D01*
X89748Y1729414D01*
X88405Y1729529D01*
Y1730564D01*
G01X90213Y1732361D02*
X89852Y1732629D01*
X89645Y1732859D01*
X89542Y1733166D01*
X89645Y1733434D01*
X89852Y1733626D01*
X90162Y1733779D01*
X90523Y1733817D01*
X90833Y1733779D01*
X91143Y1733626D01*
X91402Y1733396D01*
X91505Y1733127D01*
X91402Y1732821D01*
X91092Y1732552D01*
X90627Y1732399D01*
X90110Y1732361D01*
X89438Y1732437D01*
X89077Y1732552D01*
X88715Y1732744D01*
X88457Y1733012D01*
X88405Y1733281D01*
X88508Y1733549D01*
X88767Y1733741D01*
G01X95674Y1722812D02*
X92574D01*
Y1723771D01*
X92729Y1724077D01*
X92936Y1724269D01*
X93349Y1724346D01*
X93762Y1724269D01*
X94021Y1724039D01*
X94176Y1723771D01*
Y1722812D01*
G01Y1723771D02*
X95674Y1724346D01*
G01Y1726679D02*
X92574D01*
X93194Y1726219D01*
G01X95674D02*
Y1727139D01*
G01X95209Y1728936D02*
X95467Y1729166D01*
X95622Y1729434D01*
X95674Y1729779D01*
X95571Y1730124D01*
X95364Y1730392D01*
X95002Y1730584D01*
X94589Y1730622D01*
X94176Y1730546D01*
X93917Y1730354D01*
X93711Y1730086D01*
X93659Y1729817D01*
X93711Y1729549D01*
X93917Y1729204D01*
X92574Y1729319D01*
Y1730354D01*
G01X95674Y1732802D02*
X95002Y1732879D01*
X94434Y1732994D01*
X93917Y1733147D01*
X93349Y1733339D01*
X92574Y1733646D01*
Y1732112D01*
G01X87437Y1723022D02*
X84337D01*
Y1723981D01*
X84492Y1724287D01*
X84699Y1724479D01*
X85112Y1724556D01*
X85525Y1724479D01*
X85784Y1724249D01*
X85939Y1723981D01*
Y1723022D01*
G01Y1723981D02*
X87437Y1724556D01*
G01Y1726889D02*
X84337D01*
X84957Y1726429D01*
G01X87437D02*
Y1727349D01*
G01X86972Y1729146D02*
X87230Y1729376D01*
X87385Y1729644D01*
X87437Y1729989D01*
X87334Y1730334D01*
X87127Y1730602D01*
X86765Y1730794D01*
X86352Y1730832D01*
X85939Y1730756D01*
X85680Y1730564D01*
X85474Y1730296D01*
X85422Y1730027D01*
X85474Y1729759D01*
X85680Y1729414D01*
X84337Y1729529D01*
Y1730564D01*
G01X86972Y1732246D02*
X87230Y1732476D01*
X87385Y1732744D01*
X87437Y1733089D01*
X87334Y1733434D01*
X87127Y1733702D01*
X86765Y1733894D01*
X86352Y1733932D01*
X85939Y1733856D01*
X85680Y1733664D01*
X85474Y1733396D01*
X85422Y1733127D01*
X85474Y1732859D01*
X85680Y1732514D01*
X84337Y1732629D01*
Y1733664D01*
G01X88070Y1721192D02*
X87840Y1721347D01*
X87572Y1721450D01*
X87265D01*
X86920Y1721295D01*
X86652Y1721037D01*
X86460Y1720727D01*
X86307Y1720210D01*
X86269Y1719745D01*
X86345Y1719280D01*
X86460Y1718970D01*
X86690Y1718660D01*
X86959Y1718453D01*
X87227Y1718350D01*
X87495D01*
X87764Y1718453D01*
X87994Y1718608D01*
X88185Y1718815D01*
G01X90327Y1718350D02*
X90595Y1718402D01*
X90902Y1718557D01*
X91094Y1718815D01*
X91170Y1719177D01*
X91094Y1719538D01*
X90864Y1719848D01*
X90519Y1720003D01*
X90135D01*
X89905Y1720107D01*
X89714Y1720365D01*
X89637Y1720727D01*
X89752Y1721088D01*
X90020Y1721347D01*
X90327Y1721450D01*
X90634Y1721347D01*
X90902Y1721088D01*
X91017Y1720727D01*
X90940Y1720365D01*
X90749Y1720107D01*
X90519Y1720003D01*
X90135D01*
X89790Y1719848D01*
X89560Y1719538D01*
X89484Y1719177D01*
X89560Y1718815D01*
X89752Y1718557D01*
X90059Y1718402D01*
X90327Y1718350D01*
G01X93427D02*
X93695Y1718402D01*
X94002Y1718557D01*
X94194Y1718815D01*
X94270Y1719177D01*
X94194Y1719538D01*
X93964Y1719848D01*
X93619Y1720003D01*
X93235D01*
X93005Y1720107D01*
X92814Y1720365D01*
X92737Y1720727D01*
X92852Y1721088D01*
X93120Y1721347D01*
X93427Y1721450D01*
X93734Y1721347D01*
X94002Y1721088D01*
X94117Y1720727D01*
X94040Y1720365D01*
X93849Y1720107D01*
X93619Y1720003D01*
X93235D01*
X92890Y1719848D01*
X92660Y1719538D01*
X92584Y1719177D01*
X92660Y1718815D01*
X92852Y1718557D01*
X93159Y1718402D01*
X93427Y1718350D01*
G01X87808Y1743000D02*
X87578Y1743155D01*
X87310Y1743258D01*
X87003D01*
X86658Y1743103D01*
X86390Y1742845D01*
X86198Y1742535D01*
X86045Y1742018D01*
X86007Y1741553D01*
X86083Y1741088D01*
X86198Y1740778D01*
X86428Y1740468D01*
X86697Y1740261D01*
X86965Y1740158D01*
X87233D01*
X87502Y1740261D01*
X87732Y1740416D01*
X87923Y1740623D01*
G01X89413Y1740520D02*
X89682Y1740261D01*
X89988Y1740158D01*
X90295Y1740261D01*
X90563Y1740571D01*
X90755Y1741036D01*
X90832Y1741501D01*
Y1742070D01*
X90755Y1742535D01*
X90563Y1742948D01*
X90333Y1743155D01*
X90065Y1743258D01*
X89758Y1743155D01*
X89528Y1742948D01*
X89375Y1742638D01*
X89298Y1742225D01*
X89375Y1741863D01*
X89567Y1741501D01*
X89797Y1741295D01*
X90065Y1741243D01*
X90372Y1741346D01*
X90602Y1741605D01*
X90832Y1742070D01*
G01X93165Y1740158D02*
Y1743258D01*
X92705Y1742638D01*
G01Y1740158D02*
X93625D01*
G01X86909Y1738460D02*
X86679Y1738615D01*
X86411Y1738718D01*
X86104D01*
X85759Y1738563D01*
X85491Y1738305D01*
X85299Y1737995D01*
X85146Y1737478D01*
X85108Y1737013D01*
X85184Y1736548D01*
X85299Y1736238D01*
X85529Y1735928D01*
X85798Y1735721D01*
X86066Y1735618D01*
X86334D01*
X86603Y1735721D01*
X86833Y1735876D01*
X87024Y1736083D01*
G01X89166Y1735618D02*
X89434Y1735670D01*
X89741Y1735825D01*
X89933Y1736083D01*
X90009Y1736445D01*
X89933Y1736806D01*
X89703Y1737116D01*
X89358Y1737271D01*
X88974D01*
X88744Y1737375D01*
X88553Y1737633D01*
X88476Y1737995D01*
X88591Y1738356D01*
X88859Y1738615D01*
X89166Y1738718D01*
X89473Y1738615D01*
X89741Y1738356D01*
X89856Y1737995D01*
X89779Y1737633D01*
X89588Y1737375D01*
X89358Y1737271D01*
X88974D01*
X88629Y1737116D01*
X88399Y1736806D01*
X88323Y1736445D01*
X88399Y1736083D01*
X88591Y1735825D01*
X88898Y1735670D01*
X89166Y1735618D01*
G01X91614Y1735980D02*
X91883Y1735721D01*
X92189Y1735618D01*
X92496Y1735721D01*
X92764Y1736031D01*
X92956Y1736496D01*
X93033Y1736961D01*
Y1737530D01*
X92956Y1737995D01*
X92764Y1738408D01*
X92534Y1738615D01*
X92266Y1738718D01*
X91959Y1738615D01*
X91729Y1738408D01*
X91576Y1738098D01*
X91499Y1737685D01*
X91576Y1737323D01*
X91768Y1736961D01*
X91998Y1736755D01*
X92266Y1736703D01*
X92573Y1736806D01*
X92803Y1737065D01*
X93033Y1737530D01*
G01X85331Y1751527D02*
Y1744927D01*
G01X77831Y1744827D02*
Y1751627D01*
X92831D01*
Y1744827D01*
X77831D01*
G01X84691Y1772603D02*
Y1769603D01*
G01X87791Y1769503D02*
X81591D01*
Y1772703D01*
X87791D01*
Y1769503D01*
G01X96893Y1755259D02*
Y1758359D01*
X97852D01*
X98158Y1758204D01*
X98350Y1757997D01*
X98427Y1757584D01*
X98350Y1757171D01*
X98120Y1756912D01*
X97852Y1756757D01*
X96893D01*
G01X97852D02*
X98427Y1755259D01*
G01X100032Y1756551D02*
X100300Y1756912D01*
X100530Y1757119D01*
X100837Y1757222D01*
X101105Y1757119D01*
X101297Y1756912D01*
X101450Y1756602D01*
X101488Y1756241D01*
X101450Y1755931D01*
X101297Y1755621D01*
X101067Y1755362D01*
X100798Y1755259D01*
X100492Y1755362D01*
X100223Y1755672D01*
X100070Y1756137D01*
X100032Y1756654D01*
X100108Y1757326D01*
X100223Y1757687D01*
X100415Y1758049D01*
X100683Y1758307D01*
X100952Y1758359D01*
X101220Y1758256D01*
X101412Y1757997D01*
G01X103860Y1755259D02*
Y1758359D01*
X103400Y1757739D01*
G01Y1755259D02*
X104320D01*
G01X92130Y1767026D02*
Y1770126D01*
X93089D01*
X93395Y1769971D01*
X93587Y1769764D01*
X93664Y1769351D01*
X93587Y1768938D01*
X93357Y1768679D01*
X93089Y1768524D01*
X92130D01*
G01X93089D02*
X93664Y1767026D01*
G01X95997D02*
X96265Y1767078D01*
X96572Y1767233D01*
X96764Y1767491D01*
X96840Y1767853D01*
X96764Y1768214D01*
X96534Y1768524D01*
X96189Y1768679D01*
X95805D01*
X95575Y1768783D01*
X95384Y1769041D01*
X95307Y1769403D01*
X95422Y1769764D01*
X95690Y1770023D01*
X95997Y1770126D01*
X96304Y1770023D01*
X96572Y1769764D01*
X96687Y1769403D01*
X96610Y1769041D01*
X96419Y1768783D01*
X96189Y1768679D01*
X95805D01*
X95460Y1768524D01*
X95230Y1768214D01*
X95154Y1767853D01*
X95230Y1767491D01*
X95422Y1767233D01*
X95729Y1767078D01*
X95997Y1767026D01*
G01X99557D02*
Y1770126D01*
X98139Y1767904D01*
X100055D01*
G01X91835Y1761704D02*
Y1764804D01*
X92794D01*
X93100Y1764649D01*
X93292Y1764442D01*
X93369Y1764029D01*
X93292Y1763616D01*
X93062Y1763357D01*
X92794Y1763202D01*
X91835D01*
G01X92794D02*
X93369Y1761704D01*
G01X95702D02*
X95970Y1761756D01*
X96277Y1761911D01*
X96469Y1762169D01*
X96545Y1762531D01*
X96469Y1762892D01*
X96239Y1763202D01*
X95894Y1763357D01*
X95510D01*
X95280Y1763461D01*
X95089Y1763719D01*
X95012Y1764081D01*
X95127Y1764442D01*
X95395Y1764701D01*
X95702Y1764804D01*
X96009Y1764701D01*
X96277Y1764442D01*
X96392Y1764081D01*
X96315Y1763719D01*
X96124Y1763461D01*
X95894Y1763357D01*
X95510D01*
X95165Y1763202D01*
X94935Y1762892D01*
X94859Y1762531D01*
X94935Y1762169D01*
X95127Y1761911D01*
X95434Y1761756D01*
X95702Y1761704D01*
G01X97959Y1762169D02*
X98189Y1761911D01*
X98457Y1761756D01*
X98802Y1761704D01*
X99147Y1761807D01*
X99415Y1762014D01*
X99607Y1762376D01*
X99645Y1762789D01*
X99569Y1763202D01*
X99377Y1763461D01*
X99109Y1763667D01*
X98840Y1763719D01*
X98572Y1763667D01*
X98227Y1763461D01*
X98342Y1764804D01*
X99377D01*
G01X82817Y1753377D02*
Y1759577D01*
X86017D01*
Y1753377D01*
X82817D01*
G01X90224Y1759577D02*
Y1753377D01*
X87024D01*
Y1759577D01*
X90224D01*
G01X78749Y1753377D02*
Y1759577D01*
X81949D01*
Y1753377D01*
X78749D01*
G01X83317Y1767490D02*
Y1760890D01*
G01X75817Y1760790D02*
Y1767590D01*
X90817D01*
Y1760790D01*
X75817D01*
G01X89449Y1791936D02*
Y1795036D01*
X90408D01*
X90714Y1794881D01*
X90906Y1794674D01*
X90983Y1794261D01*
X90906Y1793848D01*
X90676Y1793589D01*
X90408Y1793434D01*
X89449D01*
G01X90408D02*
X90983Y1791936D01*
G01X92473Y1792401D02*
X92703Y1792143D01*
X92971Y1791988D01*
X93316Y1791936D01*
X93661Y1792039D01*
X93929Y1792246D01*
X94121Y1792608D01*
X94159Y1793021D01*
X94083Y1793434D01*
X93891Y1793693D01*
X93623Y1793899D01*
X93354Y1793951D01*
X93086Y1793899D01*
X92741Y1793693D01*
X92856Y1795036D01*
X93891D01*
G01X96876Y1791936D02*
Y1795036D01*
X95458Y1792814D01*
X97374D01*
G01X89767Y1787387D02*
Y1790487D01*
X90726D01*
X91032Y1790332D01*
X91224Y1790125D01*
X91301Y1789712D01*
X91224Y1789299D01*
X90994Y1789040D01*
X90726Y1788885D01*
X89767D01*
G01X90726D02*
X91301Y1787387D01*
G01X92906Y1788679D02*
X93174Y1789040D01*
X93404Y1789247D01*
X93711Y1789350D01*
X93979Y1789247D01*
X94171Y1789040D01*
X94324Y1788730D01*
X94362Y1788369D01*
X94324Y1788059D01*
X94171Y1787749D01*
X93941Y1787490D01*
X93672Y1787387D01*
X93366Y1787490D01*
X93097Y1787800D01*
X92944Y1788265D01*
X92906Y1788782D01*
X92982Y1789454D01*
X93097Y1789815D01*
X93289Y1790177D01*
X93557Y1790435D01*
X93826Y1790487D01*
X94094Y1790384D01*
X94286Y1790125D01*
G01X96734Y1790487D02*
X96427Y1790384D01*
X96197Y1790125D01*
X96044Y1789815D01*
X95929Y1789402D01*
X95891Y1788937D01*
X95929Y1788472D01*
X96044Y1788059D01*
X96197Y1787749D01*
X96427Y1787490D01*
X96734Y1787387D01*
X97041Y1787490D01*
X97271Y1787749D01*
X97424Y1788059D01*
X97539Y1788472D01*
X97577Y1788937D01*
X97539Y1789402D01*
X97424Y1789815D01*
X97271Y1790125D01*
X97041Y1790384D01*
X96734Y1790487D01*
G01X89767Y1777330D02*
Y1780430D01*
X90726D01*
X91032Y1780275D01*
X91224Y1780068D01*
X91301Y1779655D01*
X91224Y1779242D01*
X90994Y1778983D01*
X90726Y1778828D01*
X89767D01*
G01X90726D02*
X91301Y1777330D01*
G01X93634D02*
X93902Y1777382D01*
X94209Y1777537D01*
X94401Y1777795D01*
X94477Y1778157D01*
X94401Y1778518D01*
X94171Y1778828D01*
X93826Y1778983D01*
X93442D01*
X93212Y1779087D01*
X93021Y1779345D01*
X92944Y1779707D01*
X93059Y1780068D01*
X93327Y1780327D01*
X93634Y1780430D01*
X93941Y1780327D01*
X94209Y1780068D01*
X94324Y1779707D01*
X94247Y1779345D01*
X94056Y1779087D01*
X93826Y1778983D01*
X93442D01*
X93097Y1778828D01*
X92867Y1778518D01*
X92791Y1778157D01*
X92867Y1777795D01*
X93059Y1777537D01*
X93366Y1777382D01*
X93634Y1777330D01*
G01X96006Y1779913D02*
X96236Y1780223D01*
X96504Y1780378D01*
X96811Y1780430D01*
X97194Y1780327D01*
X97462Y1780068D01*
X97539Y1779758D01*
X97501Y1779448D01*
X97347Y1779190D01*
X96581Y1778673D01*
X96236Y1778312D01*
X96006Y1777795D01*
X95929Y1777330D01*
X97539D01*
G01X89767Y1782358D02*
Y1785458D01*
X90726D01*
X91032Y1785303D01*
X91224Y1785096D01*
X91301Y1784683D01*
X91224Y1784270D01*
X90994Y1784011D01*
X90726Y1783856D01*
X89767D01*
G01X90726D02*
X91301Y1782358D01*
G01X93634D02*
X93902Y1782410D01*
X94209Y1782565D01*
X94401Y1782823D01*
X94477Y1783185D01*
X94401Y1783546D01*
X94171Y1783856D01*
X93826Y1784011D01*
X93442D01*
X93212Y1784115D01*
X93021Y1784373D01*
X92944Y1784735D01*
X93059Y1785096D01*
X93327Y1785355D01*
X93634Y1785458D01*
X93941Y1785355D01*
X94209Y1785096D01*
X94324Y1784735D01*
X94247Y1784373D01*
X94056Y1784115D01*
X93826Y1784011D01*
X93442D01*
X93097Y1783856D01*
X92867Y1783546D01*
X92791Y1783185D01*
X92867Y1782823D01*
X93059Y1782565D01*
X93366Y1782410D01*
X93634Y1782358D01*
G01X95891Y1782978D02*
X96121Y1782616D01*
X96427Y1782410D01*
X96772Y1782358D01*
X97079Y1782410D01*
X97386Y1782668D01*
X97577Y1782978D01*
X97616Y1783288D01*
X97539Y1783650D01*
X97271Y1783908D01*
X97002Y1784011D01*
X96657D01*
G01X97002D02*
X97232Y1784166D01*
X97424Y1784425D01*
X97501Y1784735D01*
X97424Y1785045D01*
X97232Y1785303D01*
X96887Y1785458D01*
X96542Y1785406D01*
X96197Y1785200D01*
G01X90338Y1796309D02*
Y1799409D01*
X91297D01*
X91603Y1799254D01*
X91795Y1799047D01*
X91872Y1798634D01*
X91795Y1798221D01*
X91565Y1797962D01*
X91297Y1797807D01*
X90338D01*
G01X91297D02*
X91872Y1796309D01*
G01X94205D02*
Y1799409D01*
X93745Y1798789D01*
G01Y1796309D02*
X94665D01*
G01X96462Y1796929D02*
X96692Y1796567D01*
X96998Y1796361D01*
X97343Y1796309D01*
X97650Y1796361D01*
X97957Y1796619D01*
X98148Y1796929D01*
X98187Y1797239D01*
X98110Y1797601D01*
X97842Y1797859D01*
X97573Y1797962D01*
X97228D01*
G01X97573D02*
X97803Y1798117D01*
X97995Y1798376D01*
X98072Y1798686D01*
X97995Y1798996D01*
X97803Y1799254D01*
X97458Y1799409D01*
X97113Y1799357D01*
X96768Y1799151D01*
G01X99753Y1796671D02*
X100022Y1796412D01*
X100328Y1796309D01*
X100635Y1796412D01*
X100903Y1796722D01*
X101095Y1797187D01*
X101172Y1797652D01*
Y1798221D01*
X101095Y1798686D01*
X100903Y1799099D01*
X100673Y1799306D01*
X100405Y1799409D01*
X100098Y1799306D01*
X99868Y1799099D01*
X99715Y1798789D01*
X99638Y1798376D01*
X99715Y1798014D01*
X99907Y1797652D01*
X100137Y1797446D01*
X100405Y1797394D01*
X100712Y1797497D01*
X100942Y1797756D01*
X101172Y1798221D01*
G01X148326Y346024D02*
X111514D01*
Y118D01*
X148326D01*
Y346024D01*
G01X101204Y8567D02*
Y11667D01*
X102163D01*
X102469Y11512D01*
X102661Y11305D01*
X102738Y10892D01*
X102661Y10479D01*
X102431Y10220D01*
X102163Y10065D01*
X101204D01*
G01X102163D02*
X102738Y8567D01*
G01X105531D02*
Y11667D01*
X104113Y9445D01*
X106029D01*
G01X107328Y9032D02*
X107558Y8774D01*
X107826Y8619D01*
X108171Y8567D01*
X108516Y8670D01*
X108784Y8877D01*
X108976Y9239D01*
X109014Y9652D01*
X108938Y10065D01*
X108746Y10324D01*
X108478Y10530D01*
X108209Y10582D01*
X107941Y10530D01*
X107596Y10324D01*
X107711Y11667D01*
X108746D01*
G01X101204Y4334D02*
Y7434D01*
X102163D01*
X102469Y7279D01*
X102661Y7072D01*
X102738Y6659D01*
X102661Y6246D01*
X102431Y5987D01*
X102163Y5832D01*
X101204D01*
G01X102163D02*
X102738Y4334D01*
G01X104343Y5626D02*
X104611Y5987D01*
X104841Y6194D01*
X105148Y6297D01*
X105416Y6194D01*
X105608Y5987D01*
X105761Y5677D01*
X105799Y5316D01*
X105761Y5006D01*
X105608Y4696D01*
X105378Y4437D01*
X105109Y4334D01*
X104803Y4437D01*
X104534Y4747D01*
X104381Y5212D01*
X104343Y5729D01*
X104419Y6401D01*
X104534Y6762D01*
X104726Y7124D01*
X104994Y7382D01*
X105263Y7434D01*
X105531Y7331D01*
X105723Y7072D01*
G01X107328Y4799D02*
X107558Y4541D01*
X107826Y4386D01*
X108171Y4334D01*
X108516Y4437D01*
X108784Y4644D01*
X108976Y5006D01*
X109014Y5419D01*
X108938Y5832D01*
X108746Y6091D01*
X108478Y6297D01*
X108209Y6349D01*
X107941Y6297D01*
X107596Y6091D01*
X107711Y7434D01*
X108746D01*
G01X118621Y53288D02*
Y1122D01*
G01D02*
X418149D01*
G01X112464Y12371D02*
X112694Y12009D01*
X113000Y11803D01*
X113345Y11751D01*
X113652Y11803D01*
X113959Y12061D01*
X114150Y12371D01*
X114189Y12681D01*
X114112Y13043D01*
X113844Y13301D01*
X113575Y13404D01*
X113230D01*
G01X113575D02*
X113805Y13559D01*
X113997Y13818D01*
X114074Y14128D01*
X113997Y14438D01*
X113805Y14696D01*
X113460Y14851D01*
X113115Y14799D01*
X112770Y14593D01*
G01X115679Y14334D02*
X115909Y14644D01*
X116177Y14799D01*
X116484Y14851D01*
X116867Y14748D01*
X117135Y14489D01*
X117212Y14179D01*
X117174Y13869D01*
X117020Y13611D01*
X116254Y13094D01*
X115909Y12733D01*
X115679Y12216D01*
X115602Y11751D01*
X117212D01*
G01X99253Y34453D02*
X105453D01*
Y31253D01*
X99253D01*
Y34453D01*
G01X104320Y21680D02*
X110520D01*
Y18480D01*
X104320D01*
Y21680D01*
G01X99253Y29920D02*
X105453D01*
Y26720D01*
X99253D01*
Y29920D01*
G01X99168Y25803D02*
X105368D01*
Y22603D01*
X99168D01*
Y25803D01*
G01X104320Y17447D02*
X110520D01*
Y14247D01*
X104320D01*
Y17447D01*
G01X109615Y44685D02*
X103415D01*
Y47885D01*
X109615D01*
Y44685D01*
G01X103407Y43403D02*
X109607D01*
Y40203D01*
X103407D01*
Y43403D01*
G01X99253Y39038D02*
X105453D01*
Y35838D01*
X99253D01*
Y39038D01*
G01X418149Y53288D02*
X118621D01*
G01X102612Y79786D02*
X108812D01*
Y76586D01*
X102612D01*
Y79786D01*
G01X108868Y82880D02*
Y76680D01*
X105668D01*
Y82880D01*
X108868D01*
G01X104986Y64830D02*
X101886D01*
Y65789D01*
X102041Y66095D01*
X102248Y66287D01*
X102661Y66364D01*
X103074Y66287D01*
X103333Y66057D01*
X103488Y65789D01*
Y64830D01*
G01Y65789D02*
X104986Y66364D01*
G01Y68697D02*
X101886D01*
X102506Y68237D01*
G01X104986D02*
Y69157D01*
G01Y71797D02*
X101886D01*
X102506Y71337D01*
G01X104986D02*
Y72257D01*
G01X104366Y74054D02*
X104728Y74284D01*
X104934Y74590D01*
X104986Y74935D01*
X104934Y75242D01*
X104676Y75549D01*
X104366Y75740D01*
X104056Y75779D01*
X103694Y75702D01*
X103436Y75434D01*
X103333Y75165D01*
Y74820D01*
G01Y75165D02*
X103178Y75395D01*
X102919Y75587D01*
X102609Y75664D01*
X102299Y75587D01*
X102041Y75395D01*
X101886Y75050D01*
X101938Y74705D01*
X102144Y74360D01*
G01X105663Y73530D02*
Y79730D01*
X108863D01*
Y73530D01*
X105663D01*
G01X101202Y59850D02*
X107402D01*
Y56650D01*
X101202D01*
Y59850D01*
G01X104823Y84689D02*
X101723D01*
Y85648D01*
X101878Y85954D01*
X102085Y86146D01*
X102498Y86223D01*
X102911Y86146D01*
X103170Y85916D01*
X103325Y85648D01*
Y84689D01*
G01Y85648D02*
X104823Y86223D01*
G01Y88556D02*
X104771Y88824D01*
X104616Y89131D01*
X104358Y89323D01*
X103996Y89399D01*
X103635Y89323D01*
X103325Y89093D01*
X103170Y88748D01*
Y88364D01*
X103066Y88134D01*
X102808Y87943D01*
X102446Y87866D01*
X102085Y87981D01*
X101826Y88249D01*
X101723Y88556D01*
X101826Y88863D01*
X102085Y89131D01*
X102446Y89246D01*
X102808Y89169D01*
X103066Y88978D01*
X103170Y88748D01*
Y88364D01*
X103325Y88019D01*
X103635Y87789D01*
X103996Y87713D01*
X104358Y87789D01*
X104616Y87981D01*
X104771Y88288D01*
X104823Y88556D01*
G01Y91579D02*
X104151Y91656D01*
X103583Y91771D01*
X103066Y91924D01*
X102498Y92116D01*
X101723Y92423D01*
Y90889D01*
G01X118621Y228288D02*
Y176122D01*
G01D02*
X418149D01*
G01Y228288D02*
X118621D01*
G01X109195Y329268D02*
Y332368D01*
X108735Y331748D01*
G01Y329268D02*
X109655D01*
G01X105759Y367064D02*
X105989Y366702D01*
X106295Y366496D01*
X106640Y366444D01*
X106947Y366496D01*
X107254Y366754D01*
X107445Y367064D01*
X107484Y367374D01*
X107407Y367736D01*
X107139Y367994D01*
X106870Y368097D01*
X106525D01*
G01X106870D02*
X107100Y368252D01*
X107292Y368511D01*
X107369Y368821D01*
X107292Y369131D01*
X107100Y369389D01*
X106755Y369544D01*
X106410Y369492D01*
X106065Y369286D01*
G01X108974Y369027D02*
X109204Y369337D01*
X109472Y369492D01*
X109779Y369544D01*
X110162Y369441D01*
X110430Y369182D01*
X110507Y368872D01*
X110469Y368562D01*
X110315Y368304D01*
X109549Y367787D01*
X109204Y367426D01*
X108974Y366909D01*
X108897Y366444D01*
X110507D01*
G01X148326Y694055D02*
X111514D01*
Y348149D01*
X148326D01*
Y694055D01*
G01X118621Y403288D02*
Y351122D01*
G01D02*
X418149D01*
G01X98993Y392820D02*
X105193D01*
Y389620D01*
X98993D01*
Y392820D01*
G01Y378180D02*
X105193D01*
Y374980D01*
X98993D01*
Y378180D01*
G01Y387835D02*
X105193D01*
Y384635D01*
X98993D01*
Y387835D01*
G01Y382986D02*
X105193D01*
Y379786D01*
X98993D01*
Y382986D01*
G01Y373509D02*
X105193D01*
Y370309D01*
X98993D01*
Y373509D01*
G01Y397624D02*
X105193D01*
Y394424D01*
X98993D01*
Y397624D01*
G01X104889Y411907D02*
X101789D01*
Y412866D01*
X101944Y413172D01*
X102151Y413364D01*
X102564Y413441D01*
X102977Y413364D01*
X103236Y413134D01*
X103391Y412866D01*
Y411907D01*
G01Y412866D02*
X104889Y413441D01*
G01Y415774D02*
X101789D01*
X102409Y415314D01*
G01X104889D02*
Y416234D01*
G01Y418874D02*
X101789D01*
X102409Y418414D01*
G01X104889D02*
Y419334D01*
G01Y421897D02*
X104217Y421974D01*
X103649Y422089D01*
X103132Y422242D01*
X102564Y422434D01*
X101789Y422741D01*
Y421207D01*
G01X99269Y401952D02*
X105469D01*
Y398752D01*
X99269D01*
Y401952D01*
G01X418149Y403288D02*
X118621D01*
G01X102993Y427704D02*
X109193D01*
Y424504D01*
X102993D01*
Y427704D01*
G01X104494Y429603D02*
X101394D01*
Y430562D01*
X101549Y430868D01*
X101756Y431060D01*
X102169Y431137D01*
X102582Y431060D01*
X102841Y430830D01*
X102996Y430562D01*
Y429603D01*
G01Y430562D02*
X104494Y431137D01*
G01X104132Y432818D02*
X104391Y433087D01*
X104494Y433393D01*
X104391Y433700D01*
X104081Y433968D01*
X103616Y434160D01*
X103151Y434237D01*
X102582D01*
X102117Y434160D01*
X101704Y433968D01*
X101497Y433738D01*
X101394Y433470D01*
X101497Y433163D01*
X101704Y432933D01*
X102014Y432780D01*
X102427Y432703D01*
X102789Y432780D01*
X103151Y432972D01*
X103357Y433202D01*
X103409Y433470D01*
X103306Y433777D01*
X103047Y434007D01*
X102582Y434237D01*
G01X103874Y435727D02*
X104236Y435957D01*
X104442Y436263D01*
X104494Y436608D01*
X104442Y436915D01*
X104184Y437222D01*
X103874Y437413D01*
X103564Y437452D01*
X103202Y437375D01*
X102944Y437107D01*
X102841Y436838D01*
Y436493D01*
G01Y436838D02*
X102686Y437068D01*
X102427Y437260D01*
X102117Y437337D01*
X101807Y437260D01*
X101549Y437068D01*
X101394Y436723D01*
X101446Y436378D01*
X101652Y436033D01*
G01X109268Y430779D02*
Y424579D01*
X106068D01*
Y430779D01*
X109268D01*
G01X106068Y421429D02*
Y427629D01*
X109268D01*
Y421429D01*
X106068D01*
G01X118622Y578288D02*
Y526122D01*
G01D02*
X418150D01*
G01Y578288D02*
X118622D01*
G01X108259Y679814D02*
Y682914D01*
X107799Y682294D01*
G01Y679814D02*
X108719D01*
G01X98682Y686725D02*
Y684503D01*
X98835Y684038D01*
X99142Y683728D01*
X99525Y683625D01*
X99908Y683728D01*
X100215Y684038D01*
X100368Y684503D01*
Y686725D01*
G01X101782Y684245D02*
X102012Y683883D01*
X102318Y683677D01*
X102663Y683625D01*
X102970Y683677D01*
X103277Y683935D01*
X103468Y684245D01*
X103507Y684555D01*
X103430Y684917D01*
X103162Y685175D01*
X102893Y685278D01*
X102548D01*
G01X102893D02*
X103123Y685433D01*
X103315Y685692D01*
X103392Y686002D01*
X103315Y686312D01*
X103123Y686570D01*
X102778Y686725D01*
X102433Y686673D01*
X102088Y686467D01*
G01X148326Y1042087D02*
X111514D01*
Y696181D01*
X148326D01*
Y1042087D01*
G01X118622Y753288D02*
Y701122D01*
G01D02*
X418150D01*
G01X105807Y710153D02*
X106037Y709791D01*
X106343Y709585D01*
X106688Y709533D01*
X106995Y709585D01*
X107302Y709843D01*
X107493Y710153D01*
X107532Y710463D01*
X107455Y710825D01*
X107187Y711083D01*
X106918Y711186D01*
X106573D01*
G01X106918D02*
X107148Y711341D01*
X107340Y711600D01*
X107417Y711910D01*
X107340Y712220D01*
X107148Y712478D01*
X106803Y712633D01*
X106458Y712581D01*
X106113Y712375D01*
G01X109022Y712116D02*
X109252Y712426D01*
X109520Y712581D01*
X109827Y712633D01*
X110210Y712530D01*
X110478Y712271D01*
X110555Y711961D01*
X110517Y711651D01*
X110363Y711393D01*
X109597Y710876D01*
X109252Y710515D01*
X109022Y709998D01*
X108945Y709533D01*
X110555D01*
G01X99531Y722345D02*
X105731D01*
Y719145D01*
X99531D01*
Y722345D01*
G01Y731998D02*
X105731D01*
Y728798D01*
X99531D01*
Y731998D01*
G01Y727057D02*
X105731D01*
Y723857D01*
X99531D01*
Y727057D01*
G01Y717537D02*
X105731D01*
Y714337D01*
X99531D01*
Y717537D01*
G01X105871Y743539D02*
X99671D01*
Y746739D01*
X105871D01*
Y743539D01*
G01X99531Y736848D02*
X105731D01*
Y733648D01*
X99531D01*
Y736848D01*
G01Y741562D02*
X105731D01*
Y738362D01*
X99531D01*
Y741562D01*
G01X99995Y751081D02*
X106195D01*
Y747881D01*
X99995D01*
Y751081D01*
G01X418150Y753288D02*
X118622D01*
G01X102917Y775700D02*
X109117D01*
Y772500D01*
X102917D01*
Y775700D01*
G01X108753Y780600D02*
X105653D01*
Y781559D01*
X105808Y781865D01*
X106015Y782057D01*
X106428Y782134D01*
X106841Y782057D01*
X107100Y781827D01*
X107255Y781559D01*
Y780600D01*
G01Y781559D02*
X108753Y782134D01*
G01X108391Y783815D02*
X108650Y784084D01*
X108753Y784390D01*
X108650Y784697D01*
X108340Y784965D01*
X107875Y785157D01*
X107410Y785234D01*
X106841D01*
X106376Y785157D01*
X105963Y784965D01*
X105756Y784735D01*
X105653Y784467D01*
X105756Y784160D01*
X105963Y783930D01*
X106273Y783777D01*
X106686Y783700D01*
X107048Y783777D01*
X107410Y783969D01*
X107616Y784199D01*
X107668Y784467D01*
X107565Y784774D01*
X107306Y785004D01*
X106841Y785234D01*
G01X108753Y787490D02*
X108081Y787567D01*
X107513Y787682D01*
X106996Y787835D01*
X106428Y788027D01*
X105653Y788334D01*
Y786800D01*
G01X109215Y778824D02*
Y772624D01*
X106015D01*
Y778824D01*
X109215D01*
G01X109065Y757848D02*
X105965D01*
Y758807D01*
X106120Y759113D01*
X106327Y759305D01*
X106740Y759382D01*
X107153Y759305D01*
X107412Y759075D01*
X107567Y758807D01*
Y757848D01*
G01Y758807D02*
X109065Y759382D01*
G01Y761715D02*
X105965D01*
X106585Y761255D01*
G01X109065D02*
Y762175D01*
G01X106482Y764087D02*
X106172Y764317D01*
X106017Y764585D01*
X105965Y764892D01*
X106068Y765275D01*
X106327Y765543D01*
X106637Y765620D01*
X106947Y765582D01*
X107205Y765428D01*
X107722Y764662D01*
X108083Y764317D01*
X108600Y764087D01*
X109065Y764010D01*
Y765620D01*
G01Y767915D02*
X105965D01*
X106585Y767455D01*
G01X109065D02*
Y768375D01*
G01X106017Y769476D02*
Y775676D01*
X109217D01*
Y769476D01*
X106017D01*
G01X118621Y928288D02*
Y876122D01*
G01D02*
X418149D01*
G01Y928288D02*
X118621D01*
G01X103950Y1000737D02*
X104142Y1000427D01*
X104372Y1000220D01*
X104640Y1000117D01*
X104947Y1000220D01*
X105177Y1000427D01*
X105407Y1000737D01*
X105484Y1001150D01*
Y1003217D01*
G01X106974Y1000737D02*
X107204Y1000375D01*
X107510Y1000169D01*
X107855Y1000117D01*
X108162Y1000169D01*
X108469Y1000427D01*
X108660Y1000737D01*
X108699Y1001047D01*
X108622Y1001409D01*
X108354Y1001667D01*
X108085Y1001770D01*
X107740D01*
G01X108085D02*
X108315Y1001925D01*
X108507Y1002184D01*
X108584Y1002494D01*
X108507Y1002804D01*
X108315Y1003062D01*
X107970Y1003217D01*
X107625Y1003165D01*
X107280Y1002959D01*
G01X108889Y1025931D02*
Y1029031D01*
X108429Y1028411D01*
G01Y1025931D02*
X109349D01*
G01X148326Y1390118D02*
X111514D01*
Y1044212D01*
X148326D01*
Y1390118D01*
G01X105142Y1060484D02*
X105372Y1060122D01*
X105678Y1059916D01*
X106023Y1059864D01*
X106330Y1059916D01*
X106637Y1060174D01*
X106828Y1060484D01*
X106867Y1060794D01*
X106790Y1061156D01*
X106522Y1061414D01*
X106253Y1061517D01*
X105908D01*
G01X106253D02*
X106483Y1061672D01*
X106675Y1061931D01*
X106752Y1062241D01*
X106675Y1062551D01*
X106483Y1062809D01*
X106138Y1062964D01*
X105793Y1062912D01*
X105448Y1062706D01*
G01X108357Y1062447D02*
X108587Y1062757D01*
X108855Y1062912D01*
X109162Y1062964D01*
X109545Y1062861D01*
X109813Y1062602D01*
X109890Y1062292D01*
X109852Y1061982D01*
X109698Y1061724D01*
X108932Y1061207D01*
X108587Y1060846D01*
X108357Y1060329D01*
X108280Y1059864D01*
X109890D01*
G01X99664Y1069115D02*
X105864D01*
Y1065915D01*
X99664D01*
Y1069115D01*
G01X118621Y1103288D02*
Y1051122D01*
G01D02*
X418149D01*
G01X99664Y1093636D02*
X105864D01*
Y1090436D01*
X99664D01*
Y1093636D01*
G01Y1073826D02*
X105864D01*
Y1070626D01*
X99664D01*
Y1073826D01*
G01Y1083391D02*
X105864D01*
Y1080191D01*
X99664D01*
Y1083391D01*
G01Y1078501D02*
X105864D01*
Y1075301D01*
X99664D01*
Y1078501D01*
G01Y1088695D02*
X105864D01*
Y1085495D01*
X99664D01*
Y1088695D01*
G01X105957Y1094803D02*
X99757D01*
Y1098003D01*
X105957D01*
Y1094803D01*
G01X103704Y1105878D02*
X100604D01*
Y1106837D01*
X100759Y1107143D01*
X100966Y1107335D01*
X101379Y1107412D01*
X101792Y1107335D01*
X102051Y1107105D01*
X102206Y1106837D01*
Y1105878D01*
G01Y1106837D02*
X103704Y1107412D01*
G01Y1109745D02*
X100604D01*
X101224Y1109285D01*
G01X103704D02*
Y1110205D01*
G01X101121Y1112117D02*
X100811Y1112347D01*
X100656Y1112615D01*
X100604Y1112922D01*
X100707Y1113305D01*
X100966Y1113573D01*
X101276Y1113650D01*
X101586Y1113612D01*
X101844Y1113458D01*
X102361Y1112692D01*
X102722Y1112347D01*
X103239Y1112117D01*
X103704Y1112040D01*
Y1113650D01*
G01X103239Y1115102D02*
X103497Y1115332D01*
X103652Y1115600D01*
X103704Y1115945D01*
X103601Y1116290D01*
X103394Y1116558D01*
X103032Y1116750D01*
X102619Y1116788D01*
X102206Y1116712D01*
X101947Y1116520D01*
X101741Y1116252D01*
X101689Y1115983D01*
X101741Y1115715D01*
X101947Y1115370D01*
X100604Y1115485D01*
Y1116520D01*
G01X107219Y1117490D02*
Y1123690D01*
X110419D01*
Y1117490D01*
X107219D01*
G01X104355Y1104135D02*
X110555D01*
Y1100935D01*
X104355D01*
Y1104135D01*
G01X418149Y1103288D02*
X118621D01*
G01X104159Y1123766D02*
X110359D01*
Y1120566D01*
X104159D01*
Y1123766D01*
G01X105349Y1130022D02*
X102249D01*
Y1130981D01*
X102404Y1131287D01*
X102611Y1131479D01*
X103024Y1131556D01*
X103437Y1131479D01*
X103696Y1131249D01*
X103851Y1130981D01*
Y1130022D01*
G01Y1130981D02*
X105349Y1131556D01*
G01Y1133889D02*
X102249D01*
X102869Y1133429D01*
G01X105349D02*
Y1134349D01*
G01X102249Y1136989D02*
X102352Y1136682D01*
X102611Y1136452D01*
X102921Y1136299D01*
X103334Y1136184D01*
X103799Y1136146D01*
X104264Y1136184D01*
X104677Y1136299D01*
X104987Y1136452D01*
X105246Y1136682D01*
X105349Y1136989D01*
X105246Y1137296D01*
X104987Y1137526D01*
X104677Y1137679D01*
X104264Y1137794D01*
X103799Y1137832D01*
X103334Y1137794D01*
X102921Y1137679D01*
X102611Y1137526D01*
X102352Y1137296D01*
X102249Y1136989D01*
G01X104987Y1139437D02*
X105246Y1139706D01*
X105349Y1140012D01*
X105246Y1140319D01*
X104936Y1140587D01*
X104471Y1140779D01*
X104006Y1140856D01*
X103437D01*
X102972Y1140779D01*
X102559Y1140587D01*
X102352Y1140357D01*
X102249Y1140089D01*
X102352Y1139782D01*
X102559Y1139552D01*
X102869Y1139399D01*
X103282Y1139322D01*
X103644Y1139399D01*
X104006Y1139591D01*
X104212Y1139821D01*
X104264Y1140089D01*
X104161Y1140396D01*
X103902Y1140626D01*
X103437Y1140856D01*
G01X110416Y1126838D02*
Y1120638D01*
X107216D01*
Y1126838D01*
X110416D01*
G01X118621Y1278288D02*
Y1226122D01*
G01D02*
X418149D01*
G01Y1278288D02*
X118621D01*
G01X108081Y1374958D02*
Y1378058D01*
X107621Y1377438D01*
G01Y1374958D02*
X108541D01*
G01X105835Y1408995D02*
X106065Y1408633D01*
X106371Y1408427D01*
X106716Y1408375D01*
X107023Y1408427D01*
X107330Y1408685D01*
X107521Y1408995D01*
X107560Y1409305D01*
X107483Y1409667D01*
X107215Y1409925D01*
X106946Y1410028D01*
X106601D01*
G01X106946D02*
X107176Y1410183D01*
X107368Y1410442D01*
X107445Y1410752D01*
X107368Y1411062D01*
X107176Y1411320D01*
X106831Y1411475D01*
X106486Y1411423D01*
X106141Y1411217D01*
G01X109050Y1410958D02*
X109280Y1411268D01*
X109548Y1411423D01*
X109855Y1411475D01*
X110238Y1411372D01*
X110506Y1411113D01*
X110583Y1410803D01*
X110545Y1410493D01*
X110391Y1410235D01*
X109625Y1409718D01*
X109280Y1409357D01*
X109050Y1408840D01*
X108973Y1408375D01*
X110583D01*
G01X148326Y1738150D02*
X111514D01*
Y1392244D01*
X148326D01*
Y1738150D01*
G01X118621Y1453288D02*
Y1401122D01*
G01D02*
X418149D01*
G01X98702Y1421092D02*
X104902D01*
Y1417892D01*
X98702D01*
Y1421092D01*
G01Y1435641D02*
X104902D01*
Y1432441D01*
X98702D01*
Y1435641D01*
G01Y1430795D02*
X104902D01*
Y1427595D01*
X98702D01*
Y1430795D01*
G01Y1425940D02*
X104902D01*
Y1422740D01*
X98702D01*
Y1425940D01*
G01X104968Y1446319D02*
X98768D01*
Y1449519D01*
X104968D01*
Y1446319D01*
G01X98702Y1445343D02*
X104902D01*
Y1442143D01*
X98702D01*
Y1445343D01*
G01Y1440580D02*
X104902D01*
Y1437380D01*
X98702D01*
Y1440580D01*
G01X106296Y1456832D02*
X103196D01*
Y1457791D01*
X103351Y1458097D01*
X103558Y1458289D01*
X103971Y1458366D01*
X104384Y1458289D01*
X104643Y1458059D01*
X104798Y1457791D01*
Y1456832D01*
G01Y1457791D02*
X106296Y1458366D01*
G01Y1460699D02*
X103196D01*
X103816Y1460239D01*
G01X106296D02*
Y1461159D01*
G01X103713Y1463071D02*
X103403Y1463301D01*
X103248Y1463569D01*
X103196Y1463876D01*
X103299Y1464259D01*
X103558Y1464527D01*
X103868Y1464604D01*
X104178Y1464566D01*
X104436Y1464412D01*
X104953Y1463646D01*
X105314Y1463301D01*
X105831Y1463071D01*
X106296Y1462994D01*
Y1464604D01*
G01X105934Y1466247D02*
X106193Y1466516D01*
X106296Y1466822D01*
X106193Y1467129D01*
X105883Y1467397D01*
X105418Y1467589D01*
X104953Y1467666D01*
X104384D01*
X103919Y1467589D01*
X103506Y1467397D01*
X103299Y1467167D01*
X103196Y1466899D01*
X103299Y1466592D01*
X103506Y1466362D01*
X103816Y1466209D01*
X104229Y1466132D01*
X104591Y1466209D01*
X104953Y1466401D01*
X105159Y1466631D01*
X105211Y1466899D01*
X105108Y1467206D01*
X104849Y1467436D01*
X104384Y1467666D01*
G01X98494Y1454731D02*
X104694D01*
Y1451531D01*
X98494D01*
Y1454731D01*
G01X418149Y1453288D02*
X118621D01*
G01X103865Y1471805D02*
X110065D01*
Y1468605D01*
X103865D01*
Y1471805D01*
G01X109798Y1477879D02*
X106698D01*
Y1478838D01*
X106853Y1479144D01*
X107060Y1479336D01*
X107473Y1479413D01*
X107886Y1479336D01*
X108145Y1479106D01*
X108300Y1478838D01*
Y1477879D01*
G01Y1478838D02*
X109798Y1479413D01*
G01Y1481746D02*
X106698D01*
X107318Y1481286D01*
G01X109798D02*
Y1482206D01*
G01X106698Y1484846D02*
X106801Y1484539D01*
X107060Y1484309D01*
X107370Y1484156D01*
X107783Y1484041D01*
X108248Y1484003D01*
X108713Y1484041D01*
X109126Y1484156D01*
X109436Y1484309D01*
X109695Y1484539D01*
X109798Y1484846D01*
X109695Y1485153D01*
X109436Y1485383D01*
X109126Y1485536D01*
X108713Y1485651D01*
X108248Y1485689D01*
X107783Y1485651D01*
X107370Y1485536D01*
X107060Y1485383D01*
X106801Y1485153D01*
X106698Y1484846D01*
G01X109333Y1487103D02*
X109591Y1487333D01*
X109746Y1487601D01*
X109798Y1487946D01*
X109695Y1488291D01*
X109488Y1488559D01*
X109126Y1488751D01*
X108713Y1488789D01*
X108300Y1488713D01*
X108041Y1488521D01*
X107835Y1488253D01*
X107783Y1487984D01*
X107835Y1487716D01*
X108041Y1487371D01*
X106698Y1487486D01*
Y1488521D01*
G01X110173Y1474882D02*
Y1468682D01*
X106973D01*
Y1474882D01*
X110173D01*
G01X106974Y1465532D02*
Y1471732D01*
X110174D01*
Y1465532D01*
X106974D01*
G01X118621Y1628288D02*
Y1576122D01*
G01D02*
X418149D01*
G01Y1628288D02*
X118621D01*
G01X107799Y1722973D02*
Y1726073D01*
X107339Y1725453D01*
G01Y1722973D02*
X108259D01*
G01X103758Y1730344D02*
X103950Y1730034D01*
X104180Y1729827D01*
X104448Y1729724D01*
X104755Y1729827D01*
X104985Y1730034D01*
X105215Y1730344D01*
X105292Y1730757D01*
Y1732824D01*
G01X106782Y1730189D02*
X107012Y1729931D01*
X107280Y1729776D01*
X107625Y1729724D01*
X107970Y1729827D01*
X108238Y1730034D01*
X108430Y1730396D01*
X108468Y1730809D01*
X108392Y1731222D01*
X108200Y1731481D01*
X107932Y1731687D01*
X107663Y1731739D01*
X107395Y1731687D01*
X107050Y1731481D01*
X107165Y1732824D01*
X108200D01*
G01X148326Y2086181D02*
X111514D01*
Y1740275D01*
X148326D01*
Y2086181D01*
G01X104405Y1751725D02*
X104635Y1751363D01*
X104941Y1751157D01*
X105286Y1751105D01*
X105593Y1751157D01*
X105900Y1751415D01*
X106091Y1751725D01*
X106130Y1752035D01*
X106053Y1752397D01*
X105785Y1752655D01*
X105516Y1752758D01*
X105171D01*
G01X105516D02*
X105746Y1752913D01*
X105938Y1753172D01*
X106015Y1753482D01*
X105938Y1753792D01*
X105746Y1754050D01*
X105401Y1754205D01*
X105056Y1754153D01*
X104711Y1753947D01*
G01X107620Y1753688D02*
X107850Y1753998D01*
X108118Y1754153D01*
X108425Y1754205D01*
X108808Y1754102D01*
X109076Y1753843D01*
X109153Y1753533D01*
X109115Y1753223D01*
X108961Y1752965D01*
X108195Y1752448D01*
X107850Y1752087D01*
X107620Y1751570D01*
X107543Y1751105D01*
X109153D01*
G01X100152Y1762427D02*
X106352D01*
Y1759227D01*
X100152D01*
Y1762427D01*
G01Y1772127D02*
X106352D01*
Y1768927D01*
X100152D01*
Y1772127D01*
G01Y1767322D02*
X106352D01*
Y1764122D01*
X100152D01*
Y1767322D01*
G01X118621Y1803288D02*
Y1751122D01*
G01D02*
X418149D01*
G01X106455Y1788347D02*
X100255D01*
Y1791547D01*
X106455D01*
Y1788347D01*
G01X100152Y1787171D02*
X106352D01*
Y1783971D01*
X100152D01*
Y1787171D01*
G01Y1777114D02*
X106352D01*
Y1773914D01*
X100152D01*
Y1777114D01*
G01Y1782142D02*
X106352D01*
Y1778942D01*
X100152D01*
Y1782142D01*
G01X104144Y1819828D02*
X110344D01*
Y1816628D01*
X104144D01*
Y1819828D01*
G01X110419Y1822903D02*
Y1816703D01*
X107219D01*
Y1822903D01*
X110419D01*
G01X104823Y1802876D02*
X101723D01*
Y1803835D01*
X101878Y1804141D01*
X102085Y1804333D01*
X102498Y1804410D01*
X102911Y1804333D01*
X103170Y1804103D01*
X103325Y1803835D01*
Y1802876D01*
G01Y1803835D02*
X104823Y1804410D01*
G01Y1806743D02*
X101723D01*
X102343Y1806283D01*
G01X104823D02*
Y1807203D01*
G01X104203Y1809000D02*
X104565Y1809230D01*
X104771Y1809536D01*
X104823Y1809881D01*
X104771Y1810188D01*
X104513Y1810495D01*
X104203Y1810686D01*
X103893Y1810725D01*
X103531Y1810648D01*
X103273Y1810380D01*
X103170Y1810111D01*
Y1809766D01*
G01Y1810111D02*
X103015Y1810341D01*
X102756Y1810533D01*
X102446Y1810610D01*
X102136Y1810533D01*
X101878Y1810341D01*
X101723Y1809996D01*
X101775Y1809651D01*
X101981Y1809306D01*
G01X104203Y1812100D02*
X104565Y1812330D01*
X104771Y1812636D01*
X104823Y1812981D01*
X104771Y1813288D01*
X104513Y1813595D01*
X104203Y1813786D01*
X103893Y1813825D01*
X103531Y1813748D01*
X103273Y1813480D01*
X103170Y1813211D01*
Y1812866D01*
G01Y1813211D02*
X103015Y1813441D01*
X102756Y1813633D01*
X102446Y1813710D01*
X102136Y1813633D01*
X101878Y1813441D01*
X101723Y1813096D01*
X101775Y1812751D01*
X101981Y1812406D01*
G01X107219Y1813553D02*
Y1819753D01*
X110419D01*
Y1813553D01*
X107219D01*
G01X102146Y1799824D02*
X108346D01*
Y1796624D01*
X102146D01*
Y1799824D01*
G01X418149Y1803288D02*
X118621D01*
G01X97967Y1820968D02*
Y1824068D01*
X98926D01*
X99232Y1823913D01*
X99424Y1823706D01*
X99501Y1823293D01*
X99424Y1822880D01*
X99194Y1822621D01*
X98926Y1822466D01*
X97967D01*
G01X98926D02*
X99501Y1820968D01*
G01X101106Y1823551D02*
X101336Y1823861D01*
X101604Y1824016D01*
X101911Y1824068D01*
X102294Y1823965D01*
X102562Y1823706D01*
X102639Y1823396D01*
X102601Y1823086D01*
X102447Y1822828D01*
X101681Y1822311D01*
X101336Y1821950D01*
X101106Y1821433D01*
X101029Y1820968D01*
X102639D01*
G01X104206Y1823551D02*
X104436Y1823861D01*
X104704Y1824016D01*
X105011Y1824068D01*
X105394Y1823965D01*
X105662Y1823706D01*
X105739Y1823396D01*
X105701Y1823086D01*
X105547Y1822828D01*
X104781Y1822311D01*
X104436Y1821950D01*
X104206Y1821433D01*
X104129Y1820968D01*
X105739D01*
G01X110199Y1826334D02*
X107099D01*
Y1827293D01*
X107254Y1827599D01*
X107461Y1827791D01*
X107874Y1827868D01*
X108287Y1827791D01*
X108546Y1827561D01*
X108701Y1827293D01*
Y1826334D01*
G01Y1827293D02*
X110199Y1827868D01*
G01Y1830201D02*
X107099D01*
X107719Y1829741D01*
G01X110199D02*
Y1830661D01*
G01X107099Y1833301D02*
X107202Y1832994D01*
X107461Y1832764D01*
X107771Y1832611D01*
X108184Y1832496D01*
X108649Y1832458D01*
X109114Y1832496D01*
X109527Y1832611D01*
X109837Y1832764D01*
X110096Y1832994D01*
X110199Y1833301D01*
X110096Y1833608D01*
X109837Y1833838D01*
X109527Y1833991D01*
X109114Y1834106D01*
X108649Y1834144D01*
X108184Y1834106D01*
X107771Y1833991D01*
X107461Y1833838D01*
X107202Y1833608D01*
X107099Y1833301D01*
G01X110199Y1836401D02*
X107099D01*
X107719Y1835941D01*
G01X110199D02*
Y1836861D01*
G01X118621Y1978288D02*
Y1926122D01*
G01D02*
X418149D01*
G01Y1978288D02*
X118621D01*
G01X108784Y2070877D02*
Y2073977D01*
X108324Y2073357D01*
G01Y2070877D02*
X109244D01*
G01X150047Y19336D02*
X150277Y18974D01*
X150583Y18768D01*
X150928Y18716D01*
X151235Y18768D01*
X151542Y19026D01*
X151733Y19336D01*
X151772Y19646D01*
X151695Y20008D01*
X151427Y20266D01*
X151158Y20369D01*
X150813D01*
G01X151158D02*
X151388Y20524D01*
X151580Y20783D01*
X151657Y21093D01*
X151580Y21403D01*
X151388Y21661D01*
X151043Y21816D01*
X150698Y21764D01*
X150353Y21558D01*
G01X153147Y19336D02*
X153377Y18974D01*
X153683Y18768D01*
X154028Y18716D01*
X154335Y18768D01*
X154642Y19026D01*
X154833Y19336D01*
X154872Y19646D01*
X154795Y20008D01*
X154527Y20266D01*
X154258Y20369D01*
X153913D01*
G01X154258D02*
X154488Y20524D01*
X154680Y20783D01*
X154757Y21093D01*
X154680Y21403D01*
X154488Y21661D01*
X154143Y21816D01*
X153798Y21764D01*
X153453Y21558D01*
G01X169714Y13915D02*
Y17015D01*
X170634D01*
X170941Y16860D01*
X171171Y16498D01*
X171248Y16085D01*
X171171Y15672D01*
X170979Y15362D01*
X170634Y15207D01*
X169714D01*
G01X172738Y14535D02*
X172968Y14173D01*
X173274Y13967D01*
X173619Y13915D01*
X173926Y13967D01*
X174233Y14225D01*
X174424Y14535D01*
X174463Y14845D01*
X174386Y15207D01*
X174118Y15465D01*
X173849Y15568D01*
X173504D01*
G01X173849D02*
X174079Y15723D01*
X174271Y15982D01*
X174348Y16292D01*
X174271Y16602D01*
X174079Y16860D01*
X173734Y17015D01*
X173389Y16963D01*
X173044Y16757D01*
G01X175953Y16498D02*
X176183Y16808D01*
X176451Y16963D01*
X176758Y17015D01*
X177141Y16912D01*
X177409Y16653D01*
X177486Y16343D01*
X177448Y16033D01*
X177294Y15775D01*
X176528Y15258D01*
X176183Y14897D01*
X175953Y14380D01*
X175876Y13915D01*
X177486D01*
G01X161201Y55144D02*
X155001D01*
Y58344D01*
X161201D01*
Y55144D01*
G01X164141Y66367D02*
Y69467D01*
X165100D01*
X165406Y69312D01*
X165598Y69105D01*
X165675Y68692D01*
X165598Y68279D01*
X165368Y68020D01*
X165100Y67865D01*
X164141D01*
G01X165100D02*
X165675Y66367D01*
G01X168008D02*
Y69467D01*
X167548Y68847D01*
G01Y66367D02*
X168468D01*
G01X170380Y68950D02*
X170610Y69260D01*
X170878Y69415D01*
X171185Y69467D01*
X171568Y69364D01*
X171836Y69105D01*
X171913Y68795D01*
X171875Y68485D01*
X171721Y68227D01*
X170955Y67710D01*
X170610Y67349D01*
X170380Y66832D01*
X170303Y66367D01*
X171913D01*
G01X159988Y66530D02*
X153788D01*
Y69730D01*
X159988D01*
Y66530D01*
G01X163707Y71041D02*
Y74141D01*
X164666D01*
X164972Y73986D01*
X165164Y73779D01*
X165241Y73366D01*
X165164Y72953D01*
X164934Y72694D01*
X164666Y72539D01*
X163707D01*
G01X164666D02*
X165241Y71041D01*
G01X168034D02*
Y74141D01*
X166616Y71919D01*
X168532D01*
G01X170674Y74141D02*
X170367Y74038D01*
X170137Y73779D01*
X169984Y73469D01*
X169869Y73056D01*
X169831Y72591D01*
X169869Y72126D01*
X169984Y71713D01*
X170137Y71403D01*
X170367Y71144D01*
X170674Y71041D01*
X170981Y71144D01*
X171211Y71403D01*
X171364Y71713D01*
X171479Y72126D01*
X171517Y72591D01*
X171479Y73056D01*
X171364Y73469D01*
X171211Y73779D01*
X170981Y74038D01*
X170674Y74141D01*
G01X153677Y74097D02*
X159877D01*
Y70897D01*
X153677D01*
Y74097D01*
G01X155543Y60131D02*
Y63231D01*
X156502D01*
X156808Y63076D01*
X157000Y62869D01*
X157077Y62456D01*
X157000Y62043D01*
X156770Y61784D01*
X156502Y61629D01*
X155543D01*
G01X156502D02*
X157077Y60131D01*
G01X158758Y60493D02*
X159027Y60234D01*
X159333Y60131D01*
X159640Y60234D01*
X159908Y60544D01*
X160100Y61009D01*
X160177Y61474D01*
Y62043D01*
X160100Y62508D01*
X159908Y62921D01*
X159678Y63128D01*
X159410Y63231D01*
X159103Y63128D01*
X158873Y62921D01*
X158720Y62611D01*
X158643Y62198D01*
X158720Y61836D01*
X158912Y61474D01*
X159142Y61268D01*
X159410Y61216D01*
X159717Y61319D01*
X159947Y61578D01*
X160177Y62043D01*
G01X166932Y87466D02*
Y90566D01*
X167891D01*
X168197Y90411D01*
X168389Y90204D01*
X168466Y89791D01*
X168389Y89378D01*
X168159Y89119D01*
X167891Y88964D01*
X166932D01*
G01X167891D02*
X168466Y87466D01*
G01X170799D02*
Y90566D01*
X170339Y89946D01*
G01Y87466D02*
X171259D01*
G01X160084Y86508D02*
X153884D01*
Y89708D01*
X160084D01*
Y86508D01*
G01X156864Y94116D02*
X153764D01*
Y95075D01*
X153919Y95381D01*
X154126Y95573D01*
X154539Y95650D01*
X154952Y95573D01*
X155211Y95343D01*
X155366Y95075D01*
Y94116D01*
G01Y95075D02*
X156864Y95650D01*
G01Y97983D02*
X156812Y98251D01*
X156657Y98558D01*
X156399Y98750D01*
X156037Y98826D01*
X155676Y98750D01*
X155366Y98520D01*
X155211Y98175D01*
Y97791D01*
X155107Y97561D01*
X154849Y97370D01*
X154487Y97293D01*
X154126Y97408D01*
X153867Y97676D01*
X153764Y97983D01*
X153867Y98290D01*
X154126Y98558D01*
X154487Y98673D01*
X154849Y98596D01*
X155107Y98405D01*
X155211Y98175D01*
Y97791D01*
X155366Y97446D01*
X155676Y97216D01*
X156037Y97140D01*
X156399Y97216D01*
X156657Y97408D01*
X156812Y97715D01*
X156864Y97983D01*
G01X155572Y100355D02*
X155211Y100623D01*
X155004Y100853D01*
X154901Y101160D01*
X155004Y101428D01*
X155211Y101620D01*
X155521Y101773D01*
X155882Y101811D01*
X156192Y101773D01*
X156502Y101620D01*
X156761Y101390D01*
X156864Y101121D01*
X156761Y100815D01*
X156451Y100546D01*
X155986Y100393D01*
X155469Y100355D01*
X154797Y100431D01*
X154436Y100546D01*
X154074Y100738D01*
X153816Y101006D01*
X153764Y101275D01*
X153867Y101543D01*
X154126Y101735D01*
G01X156970Y92806D02*
Y86606D01*
X153770D01*
Y92806D01*
X156970D01*
G01X161442Y82539D02*
Y85639D01*
X162401D01*
X162707Y85484D01*
X162899Y85277D01*
X162976Y84864D01*
X162899Y84451D01*
X162669Y84192D01*
X162401Y84037D01*
X161442D01*
G01X162401D02*
X162976Y82539D01*
G01X165309D02*
Y85639D01*
X164849Y85019D01*
G01Y82539D02*
X165769D01*
G01X168409D02*
Y85639D01*
X167949Y85019D01*
G01Y82539D02*
X168869D01*
G01X171509Y85639D02*
X171202Y85536D01*
X170972Y85277D01*
X170819Y84967D01*
X170704Y84554D01*
X170666Y84089D01*
X170704Y83624D01*
X170819Y83211D01*
X170972Y82901D01*
X171202Y82642D01*
X171509Y82539D01*
X171816Y82642D01*
X172046Y82901D01*
X172199Y83211D01*
X172314Y83624D01*
X172352Y84089D01*
X172314Y84554D01*
X172199Y84967D01*
X172046Y85277D01*
X171816Y85536D01*
X171509Y85639D01*
G01X153766Y83492D02*
Y89692D01*
X156966D01*
Y83492D01*
X153766D01*
G01X166075Y171126D02*
Y174226D01*
X166995D01*
X167302Y174071D01*
X167532Y173709D01*
X167609Y173296D01*
X167532Y172883D01*
X167340Y172573D01*
X166995Y172418D01*
X166075D01*
G01X169099Y171746D02*
X169329Y171384D01*
X169635Y171178D01*
X169980Y171126D01*
X170287Y171178D01*
X170594Y171436D01*
X170785Y171746D01*
X170824Y172056D01*
X170747Y172418D01*
X170479Y172676D01*
X170210Y172779D01*
X169865D01*
G01X170210D02*
X170440Y172934D01*
X170632Y173193D01*
X170709Y173503D01*
X170632Y173813D01*
X170440Y174071D01*
X170095Y174226D01*
X169750Y174174D01*
X169405Y173968D01*
G01X172314Y173709D02*
X172544Y174019D01*
X172812Y174174D01*
X173119Y174226D01*
X173502Y174123D01*
X173770Y173864D01*
X173847Y173554D01*
X173809Y173244D01*
X173655Y172986D01*
X172889Y172469D01*
X172544Y172108D01*
X172314Y171591D01*
X172237Y171126D01*
X173847D01*
G01X149901Y318042D02*
X150093Y317732D01*
X150323Y317525D01*
X150591Y317422D01*
X150898Y317525D01*
X151128Y317732D01*
X151358Y318042D01*
X151435Y318455D01*
Y320522D01*
G01X153768Y317422D02*
Y320522D01*
X153308Y319902D01*
G01Y317422D02*
X154228D01*
G01X150526Y328472D02*
X150794Y328833D01*
X151024Y329040D01*
X151331Y329143D01*
X151599Y329040D01*
X151791Y328833D01*
X151944Y328523D01*
X151982Y328162D01*
X151944Y327852D01*
X151791Y327542D01*
X151561Y327283D01*
X151292Y327180D01*
X150986Y327283D01*
X150717Y327593D01*
X150564Y328058D01*
X150526Y328575D01*
X150602Y329247D01*
X150717Y329608D01*
X150909Y329970D01*
X151177Y330228D01*
X151446Y330280D01*
X151714Y330177D01*
X151906Y329918D01*
G01X154814Y327180D02*
Y330280D01*
X153396Y328058D01*
X155312D01*
G01X168999Y345741D02*
Y348841D01*
X169919D01*
X170226Y348686D01*
X170456Y348324D01*
X170533Y347911D01*
X170456Y347498D01*
X170264Y347188D01*
X169919Y347033D01*
X168999D01*
G01X172023Y346361D02*
X172253Y345999D01*
X172559Y345793D01*
X172904Y345741D01*
X173211Y345793D01*
X173518Y346051D01*
X173709Y346361D01*
X173748Y346671D01*
X173671Y347033D01*
X173403Y347291D01*
X173134Y347394D01*
X172789D01*
G01X173134D02*
X173364Y347549D01*
X173556Y347808D01*
X173633Y348118D01*
X173556Y348428D01*
X173364Y348686D01*
X173019Y348841D01*
X172674Y348789D01*
X172329Y348583D01*
G01X175238Y348324D02*
X175468Y348634D01*
X175736Y348789D01*
X176043Y348841D01*
X176426Y348738D01*
X176694Y348479D01*
X176771Y348169D01*
X176733Y347859D01*
X176579Y347601D01*
X175813Y347084D01*
X175468Y346723D01*
X175238Y346206D01*
X175161Y345741D01*
X176771D01*
G01X150363Y347536D02*
X150593Y347174D01*
X150899Y346968D01*
X151244Y346916D01*
X151551Y346968D01*
X151858Y347226D01*
X152049Y347536D01*
X152088Y347846D01*
X152011Y348208D01*
X151743Y348466D01*
X151474Y348569D01*
X151129D01*
G01X151474D02*
X151704Y348724D01*
X151896Y348983D01*
X151973Y349293D01*
X151896Y349603D01*
X151704Y349861D01*
X151359Y350016D01*
X151014Y349964D01*
X150669Y349758D01*
G01X153463Y347536D02*
X153693Y347174D01*
X153999Y346968D01*
X154344Y346916D01*
X154651Y346968D01*
X154958Y347226D01*
X155149Y347536D01*
X155188Y347846D01*
X155111Y348208D01*
X154843Y348466D01*
X154574Y348569D01*
X154229D01*
G01X154574D02*
X154804Y348724D01*
X154996Y348983D01*
X155073Y349293D01*
X154996Y349603D01*
X154804Y349861D01*
X154459Y350016D01*
X154114Y349964D01*
X153769Y349758D01*
G01X167837Y413737D02*
X164737D01*
Y414696D01*
X164892Y415002D01*
X165099Y415194D01*
X165512Y415271D01*
X165925Y415194D01*
X166184Y414964D01*
X166339Y414696D01*
Y413737D01*
G01Y414696D02*
X167837Y415271D01*
G01Y418064D02*
X164737D01*
X166959Y416646D01*
Y418562D01*
G01X157921Y419723D02*
Y413523D01*
X154721D01*
Y419723D01*
X157921D01*
G01X163704Y406282D02*
Y409382D01*
X164663D01*
X164969Y409227D01*
X165161Y409020D01*
X165238Y408607D01*
X165161Y408194D01*
X164931Y407935D01*
X164663Y407780D01*
X163704D01*
G01X164663D02*
X165238Y406282D01*
G01X167571D02*
Y409382D01*
X167111Y408762D01*
G01Y406282D02*
X168031D01*
G01X170671D02*
Y409382D01*
X170211Y408762D01*
G01Y406282D02*
X171131D01*
G01X160015Y405975D02*
X153815D01*
Y409175D01*
X160015D01*
Y405975D01*
G01X172215Y413760D02*
X169115D01*
Y414719D01*
X169270Y415025D01*
X169477Y415217D01*
X169890Y415294D01*
X170303Y415217D01*
X170562Y414987D01*
X170717Y414719D01*
Y413760D01*
G01Y414719D02*
X172215Y415294D01*
G01Y417627D02*
X172163Y417895D01*
X172008Y418202D01*
X171750Y418394D01*
X171388Y418470D01*
X171027Y418394D01*
X170717Y418164D01*
X170562Y417819D01*
Y417435D01*
X170458Y417205D01*
X170200Y417014D01*
X169838Y416937D01*
X169477Y417052D01*
X169218Y417320D01*
X169115Y417627D01*
X169218Y417934D01*
X169477Y418202D01*
X169838Y418317D01*
X170200Y418240D01*
X170458Y418049D01*
X170562Y417819D01*
Y417435D01*
X170717Y417090D01*
X171027Y416860D01*
X171388Y416784D01*
X171750Y416860D01*
X172008Y417052D01*
X172163Y417359D01*
X172215Y417627D01*
G01X162856Y419720D02*
Y413520D01*
X159656D01*
Y419720D01*
X162856D01*
G01X163710Y437317D02*
Y440417D01*
X164669D01*
X164975Y440262D01*
X165167Y440055D01*
X165244Y439642D01*
X165167Y439229D01*
X164937Y438970D01*
X164669Y438815D01*
X163710D01*
G01X164669D02*
X165244Y437317D01*
G01X166734Y437937D02*
X166964Y437575D01*
X167270Y437369D01*
X167615Y437317D01*
X167922Y437369D01*
X168229Y437627D01*
X168420Y437937D01*
X168459Y438247D01*
X168382Y438609D01*
X168114Y438867D01*
X167845Y438970D01*
X167500D01*
G01X167845D02*
X168075Y439125D01*
X168267Y439384D01*
X168344Y439694D01*
X168267Y440004D01*
X168075Y440262D01*
X167730Y440417D01*
X167385Y440365D01*
X167040Y440159D01*
G01X160023Y434519D02*
X153823D01*
Y437719D01*
X160023D01*
Y434519D01*
G01X156846Y442424D02*
X153746D01*
Y443383D01*
X153901Y443689D01*
X154108Y443881D01*
X154521Y443958D01*
X154934Y443881D01*
X155193Y443651D01*
X155348Y443383D01*
Y442424D01*
G01Y443383D02*
X156846Y443958D01*
G01X156484Y445639D02*
X156743Y445908D01*
X156846Y446214D01*
X156743Y446521D01*
X156433Y446789D01*
X155968Y446981D01*
X155503Y447058D01*
X154934D01*
X154469Y446981D01*
X154056Y446789D01*
X153849Y446559D01*
X153746Y446291D01*
X153849Y445984D01*
X154056Y445754D01*
X154366Y445601D01*
X154779Y445524D01*
X155141Y445601D01*
X155503Y445793D01*
X155709Y446023D01*
X155761Y446291D01*
X155658Y446598D01*
X155399Y446828D01*
X154934Y447058D01*
G01X153746Y449391D02*
X153849Y449084D01*
X154108Y448854D01*
X154418Y448701D01*
X154831Y448586D01*
X155296Y448548D01*
X155761Y448586D01*
X156174Y448701D01*
X156484Y448854D01*
X156743Y449084D01*
X156846Y449391D01*
X156743Y449698D01*
X156484Y449928D01*
X156174Y450081D01*
X155761Y450196D01*
X155296Y450234D01*
X154831Y450196D01*
X154418Y450081D01*
X154108Y449928D01*
X153849Y449698D01*
X153746Y449391D01*
G01X156951Y440793D02*
Y434593D01*
X153751D01*
Y440793D01*
X156951D01*
G01X165205Y424287D02*
X162105D01*
Y425246D01*
X162260Y425552D01*
X162467Y425744D01*
X162880Y425821D01*
X163293Y425744D01*
X163552Y425514D01*
X163707Y425246D01*
Y424287D01*
G01Y425246D02*
X165205Y425821D01*
G01Y428154D02*
X162105D01*
X162725Y427694D01*
G01X165205D02*
Y428614D01*
G01Y431254D02*
X162105D01*
X162725Y430794D01*
G01X165205D02*
Y431714D01*
G01Y434814D02*
X162105D01*
X164327Y433396D01*
Y435312D01*
G01X153748Y431444D02*
Y437644D01*
X156948D01*
Y431444D01*
X153748D01*
G01X168846Y519413D02*
Y522513D01*
X169766D01*
X170073Y522358D01*
X170303Y521996D01*
X170380Y521583D01*
X170303Y521170D01*
X170111Y520860D01*
X169766Y520705D01*
X168846D01*
G01X171870Y520033D02*
X172100Y519671D01*
X172406Y519465D01*
X172751Y519413D01*
X173058Y519465D01*
X173365Y519723D01*
X173556Y520033D01*
X173595Y520343D01*
X173518Y520705D01*
X173250Y520963D01*
X172981Y521066D01*
X172636D01*
G01X172981D02*
X173211Y521221D01*
X173403Y521480D01*
X173480Y521790D01*
X173403Y522100D01*
X173211Y522358D01*
X172866Y522513D01*
X172521Y522461D01*
X172176Y522255D01*
G01X175085Y521996D02*
X175315Y522306D01*
X175583Y522461D01*
X175890Y522513D01*
X176273Y522410D01*
X176541Y522151D01*
X176618Y521841D01*
X176580Y521531D01*
X176426Y521273D01*
X175660Y520756D01*
X175315Y520395D01*
X175085Y519878D01*
X175008Y519413D01*
X176618D01*
G01X168291Y581251D02*
Y584351D01*
X169211D01*
X169518Y584196D01*
X169748Y583834D01*
X169825Y583421D01*
X169748Y583008D01*
X169556Y582698D01*
X169211Y582543D01*
X168291D01*
G01X172158Y581251D02*
Y584351D01*
X171698Y583731D01*
G01Y581251D02*
X172618D01*
G01X150373Y663045D02*
X150565Y662735D01*
X150795Y662528D01*
X151063Y662425D01*
X151370Y662528D01*
X151600Y662735D01*
X151830Y663045D01*
X151907Y663458D01*
Y665525D01*
G01X153512Y665008D02*
X153742Y665318D01*
X154010Y665473D01*
X154317Y665525D01*
X154700Y665422D01*
X154968Y665163D01*
X155045Y664853D01*
X155007Y664543D01*
X154853Y664285D01*
X154087Y663768D01*
X153742Y663407D01*
X153512Y662890D01*
X153435Y662425D01*
X155045D01*
G01X150421Y678772D02*
X150689Y679133D01*
X150919Y679340D01*
X151226Y679443D01*
X151494Y679340D01*
X151686Y679133D01*
X151839Y678823D01*
X151877Y678462D01*
X151839Y678152D01*
X151686Y677842D01*
X151456Y677583D01*
X151187Y677480D01*
X150881Y677583D01*
X150612Y677893D01*
X150459Y678358D01*
X150421Y678875D01*
X150497Y679547D01*
X150612Y679908D01*
X150804Y680270D01*
X151072Y680528D01*
X151341Y680580D01*
X151609Y680477D01*
X151801Y680218D01*
G01X154709Y677480D02*
Y680580D01*
X153291Y678358D01*
X155207D01*
G01X150466Y697320D02*
X150696Y696958D01*
X151002Y696752D01*
X151347Y696700D01*
X151654Y696752D01*
X151961Y697010D01*
X152152Y697320D01*
X152191Y697630D01*
X152114Y697992D01*
X151846Y698250D01*
X151577Y698353D01*
X151232D01*
G01X151577D02*
X151807Y698508D01*
X151999Y698767D01*
X152076Y699077D01*
X151999Y699387D01*
X151807Y699645D01*
X151462Y699800D01*
X151117Y699748D01*
X150772Y699542D01*
G01X153566Y697320D02*
X153796Y696958D01*
X154102Y696752D01*
X154447Y696700D01*
X154754Y696752D01*
X155061Y697010D01*
X155252Y697320D01*
X155291Y697630D01*
X155214Y697992D01*
X154946Y698250D01*
X154677Y698353D01*
X154332D01*
G01X154677D02*
X154907Y698508D01*
X155099Y698767D01*
X155176Y699077D01*
X155099Y699387D01*
X154907Y699645D01*
X154562Y699800D01*
X154217Y699748D01*
X153872Y699542D01*
G01X169591Y715062D02*
Y718162D01*
X170511D01*
X170818Y718007D01*
X171048Y717645D01*
X171125Y717232D01*
X171048Y716819D01*
X170856Y716509D01*
X170511Y716354D01*
X169591D01*
G01X172615Y715682D02*
X172845Y715320D01*
X173151Y715114D01*
X173496Y715062D01*
X173803Y715114D01*
X174110Y715372D01*
X174301Y715682D01*
X174340Y715992D01*
X174263Y716354D01*
X173995Y716612D01*
X173726Y716715D01*
X173381D01*
G01X173726D02*
X173956Y716870D01*
X174148Y717129D01*
X174225Y717439D01*
X174148Y717749D01*
X173956Y718007D01*
X173611Y718162D01*
X173266Y718110D01*
X172921Y717904D01*
G01X175830Y717645D02*
X176060Y717955D01*
X176328Y718110D01*
X176635Y718162D01*
X177018Y718059D01*
X177286Y717800D01*
X177363Y717490D01*
X177325Y717180D01*
X177171Y716922D01*
X176405Y716405D01*
X176060Y716044D01*
X175830Y715527D01*
X175753Y715062D01*
X177363D01*
G01X164162Y755043D02*
Y758143D01*
X165121D01*
X165427Y757988D01*
X165619Y757781D01*
X165696Y757368D01*
X165619Y756955D01*
X165389Y756696D01*
X165121Y756541D01*
X164162D01*
G01X165121D02*
X165696Y755043D01*
G01X168029D02*
Y758143D01*
X167569Y757523D01*
G01Y755043D02*
X168489D01*
G01X171129Y758143D02*
X170822Y758040D01*
X170592Y757781D01*
X170439Y757471D01*
X170324Y757058D01*
X170286Y756593D01*
X170324Y756128D01*
X170439Y755715D01*
X170592Y755405D01*
X170822Y755146D01*
X171129Y755043D01*
X171436Y755146D01*
X171666Y755405D01*
X171819Y755715D01*
X171934Y756128D01*
X171972Y756593D01*
X171934Y757058D01*
X171819Y757471D01*
X171666Y757781D01*
X171436Y758040D01*
X171129Y758143D01*
G01X160475Y755157D02*
X154275D01*
Y758357D01*
X160475D01*
Y755157D01*
G01X164206Y762500D02*
Y765600D01*
X165165D01*
X165471Y765445D01*
X165663Y765238D01*
X165740Y764825D01*
X165663Y764412D01*
X165433Y764153D01*
X165165Y763998D01*
X164206D01*
G01X165165D02*
X165740Y762500D01*
G01X168073D02*
Y765600D01*
X167613Y764980D01*
G01Y762500D02*
X168533D01*
G01X170330Y763120D02*
X170560Y762758D01*
X170866Y762552D01*
X171211Y762500D01*
X171518Y762552D01*
X171825Y762810D01*
X172016Y763120D01*
X172055Y763430D01*
X171978Y763792D01*
X171710Y764050D01*
X171441Y764153D01*
X171096D01*
G01X171441D02*
X171671Y764308D01*
X171863Y764567D01*
X171940Y764877D01*
X171863Y765187D01*
X171671Y765445D01*
X171326Y765600D01*
X170981Y765548D01*
X170636Y765342D01*
G01X160190Y762631D02*
X153990D01*
Y765831D01*
X160190D01*
Y762631D01*
G01X165063Y773963D02*
Y777063D01*
X166022D01*
X166328Y776908D01*
X166520Y776701D01*
X166597Y776288D01*
X166520Y775875D01*
X166290Y775616D01*
X166022Y775461D01*
X165063D01*
G01X166022D02*
X166597Y773963D01*
G01X169390D02*
Y777063D01*
X167972Y774841D01*
X169888D01*
G01X171302Y776546D02*
X171532Y776856D01*
X171800Y777011D01*
X172107Y777063D01*
X172490Y776960D01*
X172758Y776701D01*
X172835Y776391D01*
X172797Y776081D01*
X172643Y775823D01*
X171877Y775306D01*
X171532Y774945D01*
X171302Y774428D01*
X171225Y773963D01*
X172835D01*
G01X153588Y778273D02*
X159788D01*
Y775073D01*
X153588D01*
Y778273D01*
G01X163574Y779254D02*
Y782354D01*
X164533D01*
X164839Y782199D01*
X165031Y781992D01*
X165108Y781579D01*
X165031Y781166D01*
X164801Y780907D01*
X164533Y780752D01*
X163574D01*
G01X164533D02*
X165108Y779254D01*
G01X167441D02*
Y782354D01*
X166981Y781734D01*
G01Y779254D02*
X167901D01*
G01X170541D02*
Y782354D01*
X170081Y781734D01*
G01Y779254D02*
X171001D01*
G01X173641D02*
X173909Y779306D01*
X174216Y779461D01*
X174408Y779719D01*
X174484Y780081D01*
X174408Y780442D01*
X174178Y780752D01*
X173833Y780907D01*
X173449D01*
X173219Y781011D01*
X173028Y781269D01*
X172951Y781631D01*
X173066Y781992D01*
X173334Y782251D01*
X173641Y782354D01*
X173948Y782251D01*
X174216Y781992D01*
X174331Y781631D01*
X174254Y781269D01*
X174063Y781011D01*
X173833Y780907D01*
X173449D01*
X173104Y780752D01*
X172874Y780442D01*
X172798Y780081D01*
X172874Y779719D01*
X173066Y779461D01*
X173373Y779306D01*
X173641Y779254D01*
G01X153756Y779457D02*
Y785657D01*
X156956D01*
Y779457D01*
X153756D01*
G01X164957Y784194D02*
Y787294D01*
X165916D01*
X166222Y787139D01*
X166414Y786932D01*
X166491Y786519D01*
X166414Y786106D01*
X166184Y785847D01*
X165916Y785692D01*
X164957D01*
G01X165916D02*
X166491Y784194D01*
G01X168096Y786777D02*
X168326Y787087D01*
X168594Y787242D01*
X168901Y787294D01*
X169284Y787191D01*
X169552Y786932D01*
X169629Y786622D01*
X169591Y786312D01*
X169437Y786054D01*
X168671Y785537D01*
X168326Y785176D01*
X168096Y784659D01*
X168019Y784194D01*
X169629D01*
G01X160044Y782541D02*
X153844D01*
Y785741D01*
X160044D01*
Y782541D01*
G01X168855Y789649D02*
X165755D01*
Y790608D01*
X165910Y790914D01*
X166117Y791106D01*
X166530Y791183D01*
X166943Y791106D01*
X167202Y790876D01*
X167357Y790608D01*
Y789649D01*
G01Y790608D02*
X168855Y791183D01*
G01X168493Y792864D02*
X168752Y793133D01*
X168855Y793439D01*
X168752Y793746D01*
X168442Y794014D01*
X167977Y794206D01*
X167512Y794283D01*
X166943D01*
X166478Y794206D01*
X166065Y794014D01*
X165858Y793784D01*
X165755Y793516D01*
X165858Y793209D01*
X166065Y792979D01*
X166375Y792826D01*
X166788Y792749D01*
X167150Y792826D01*
X167512Y793018D01*
X167718Y793248D01*
X167770Y793516D01*
X167667Y793823D01*
X167408Y794053D01*
X166943Y794283D01*
G01X168855Y797076D02*
X165755D01*
X167977Y795658D01*
Y797574D01*
G01X156962Y788805D02*
Y782605D01*
X153762D01*
Y788805D01*
X156962D01*
G01X167682Y871238D02*
Y874338D01*
X168602D01*
X168909Y874183D01*
X169139Y873821D01*
X169216Y873408D01*
X169139Y872995D01*
X168947Y872685D01*
X168602Y872530D01*
X167682D01*
G01X170706Y871858D02*
X170936Y871496D01*
X171242Y871290D01*
X171587Y871238D01*
X171894Y871290D01*
X172201Y871548D01*
X172392Y871858D01*
X172431Y872168D01*
X172354Y872530D01*
X172086Y872788D01*
X171817Y872891D01*
X171472D01*
G01X171817D02*
X172047Y873046D01*
X172239Y873305D01*
X172316Y873615D01*
X172239Y873925D01*
X172047Y874183D01*
X171702Y874338D01*
X171357Y874286D01*
X171012Y874080D01*
G01X173921Y873821D02*
X174151Y874131D01*
X174419Y874286D01*
X174726Y874338D01*
X175109Y874235D01*
X175377Y873976D01*
X175454Y873666D01*
X175416Y873356D01*
X175262Y873098D01*
X174496Y872581D01*
X174151Y872220D01*
X173921Y871703D01*
X173844Y871238D01*
X175454D01*
G01X166359Y936892D02*
Y939992D01*
X167318D01*
X167624Y939837D01*
X167816Y939630D01*
X167893Y939217D01*
X167816Y938804D01*
X167586Y938545D01*
X167318Y938390D01*
X166359D01*
G01X167318D02*
X167893Y936892D01*
G01X170226D02*
X170494Y936944D01*
X170801Y937099D01*
X170993Y937357D01*
X171069Y937719D01*
X170993Y938080D01*
X170763Y938390D01*
X170418Y938545D01*
X170034D01*
X169804Y938649D01*
X169613Y938907D01*
X169536Y939269D01*
X169651Y939630D01*
X169919Y939889D01*
X170226Y939992D01*
X170533Y939889D01*
X170801Y939630D01*
X170916Y939269D01*
X170839Y938907D01*
X170648Y938649D01*
X170418Y938545D01*
X170034D01*
X169689Y938390D01*
X169459Y938080D01*
X169383Y937719D01*
X169459Y937357D01*
X169651Y937099D01*
X169958Y936944D01*
X170226Y936892D01*
G01X173326D02*
X173594Y936944D01*
X173901Y937099D01*
X174093Y937357D01*
X174169Y937719D01*
X174093Y938080D01*
X173863Y938390D01*
X173518Y938545D01*
X173134D01*
X172904Y938649D01*
X172713Y938907D01*
X172636Y939269D01*
X172751Y939630D01*
X173019Y939889D01*
X173326Y939992D01*
X173633Y939889D01*
X173901Y939630D01*
X174016Y939269D01*
X173939Y938907D01*
X173748Y938649D01*
X173518Y938545D01*
X173134D01*
X172789Y938390D01*
X172559Y938080D01*
X172483Y937719D01*
X172559Y937357D01*
X172751Y937099D01*
X173058Y936944D01*
X173326Y936892D01*
G01X166001Y942671D02*
Y945771D01*
X166960D01*
X167266Y945616D01*
X167458Y945409D01*
X167535Y944996D01*
X167458Y944583D01*
X167228Y944324D01*
X166960Y944169D01*
X166001D01*
G01X166960D02*
X167535Y942671D01*
G01X169868D02*
X170136Y942723D01*
X170443Y942878D01*
X170635Y943136D01*
X170711Y943498D01*
X170635Y943859D01*
X170405Y944169D01*
X170060Y944324D01*
X169676D01*
X169446Y944428D01*
X169255Y944686D01*
X169178Y945048D01*
X169293Y945409D01*
X169561Y945668D01*
X169868Y945771D01*
X170175Y945668D01*
X170443Y945409D01*
X170558Y945048D01*
X170481Y944686D01*
X170290Y944428D01*
X170060Y944324D01*
X169676D01*
X169331Y944169D01*
X169101Y943859D01*
X169025Y943498D01*
X169101Y943136D01*
X169293Y942878D01*
X169600Y942723D01*
X169868Y942671D01*
G01X172316Y943033D02*
X172585Y942774D01*
X172891Y942671D01*
X173198Y942774D01*
X173466Y943084D01*
X173658Y943549D01*
X173735Y944014D01*
Y944583D01*
X173658Y945048D01*
X173466Y945461D01*
X173236Y945668D01*
X172968Y945771D01*
X172661Y945668D01*
X172431Y945461D01*
X172278Y945151D01*
X172201Y944738D01*
X172278Y944376D01*
X172470Y944014D01*
X172700Y943808D01*
X172968Y943756D01*
X173275Y943859D01*
X173505Y944118D01*
X173735Y944583D01*
G01X165988Y961072D02*
Y964172D01*
X166947D01*
X167253Y964017D01*
X167445Y963810D01*
X167522Y963397D01*
X167445Y962984D01*
X167215Y962725D01*
X166947Y962570D01*
X165988D01*
G01X166947D02*
X167522Y961072D01*
G01X169203Y961434D02*
X169472Y961175D01*
X169778Y961072D01*
X170085Y961175D01*
X170353Y961485D01*
X170545Y961950D01*
X170622Y962415D01*
Y962984D01*
X170545Y963449D01*
X170353Y963862D01*
X170123Y964069D01*
X169855Y964172D01*
X169548Y964069D01*
X169318Y963862D01*
X169165Y963552D01*
X169088Y963139D01*
X169165Y962777D01*
X169357Y962415D01*
X169587Y962209D01*
X169855Y962157D01*
X170162Y962260D01*
X170392Y962519D01*
X170622Y962984D01*
G01X172955Y961072D02*
Y964172D01*
X172495Y963552D01*
G01Y961072D02*
X173415D01*
G01X166350Y954839D02*
Y957939D01*
X167309D01*
X167615Y957784D01*
X167807Y957577D01*
X167884Y957164D01*
X167807Y956751D01*
X167577Y956492D01*
X167309Y956337D01*
X166350D01*
G01X167309D02*
X167884Y954839D01*
G01X169565Y955201D02*
X169834Y954942D01*
X170140Y954839D01*
X170447Y954942D01*
X170715Y955252D01*
X170907Y955717D01*
X170984Y956182D01*
Y956751D01*
X170907Y957216D01*
X170715Y957629D01*
X170485Y957836D01*
X170217Y957939D01*
X169910Y957836D01*
X169680Y957629D01*
X169527Y957319D01*
X169450Y956906D01*
X169527Y956544D01*
X169719Y956182D01*
X169949Y955976D01*
X170217Y955924D01*
X170524Y956027D01*
X170754Y956286D01*
X170984Y956751D01*
G01X172589Y957422D02*
X172819Y957732D01*
X173087Y957887D01*
X173394Y957939D01*
X173777Y957836D01*
X174045Y957577D01*
X174122Y957267D01*
X174084Y956957D01*
X173930Y956699D01*
X173164Y956182D01*
X172819Y955821D01*
X172589Y955304D01*
X172512Y954839D01*
X174122D01*
G01X149853Y1025472D02*
X150121Y1025833D01*
X150351Y1026040D01*
X150658Y1026143D01*
X150926Y1026040D01*
X151118Y1025833D01*
X151271Y1025523D01*
X151309Y1025162D01*
X151271Y1024852D01*
X151118Y1024542D01*
X150888Y1024283D01*
X150619Y1024180D01*
X150313Y1024283D01*
X150044Y1024593D01*
X149891Y1025058D01*
X149853Y1025575D01*
X149929Y1026247D01*
X150044Y1026608D01*
X150236Y1026970D01*
X150504Y1027228D01*
X150773Y1027280D01*
X151041Y1027177D01*
X151233Y1026918D01*
G01X154141Y1024180D02*
Y1027280D01*
X152723Y1025058D01*
X154639D01*
G01X149946Y1047207D02*
X150176Y1046845D01*
X150482Y1046639D01*
X150827Y1046587D01*
X151134Y1046639D01*
X151441Y1046897D01*
X151632Y1047207D01*
X151671Y1047517D01*
X151594Y1047879D01*
X151326Y1048137D01*
X151057Y1048240D01*
X150712D01*
G01X151057D02*
X151287Y1048395D01*
X151479Y1048654D01*
X151556Y1048964D01*
X151479Y1049274D01*
X151287Y1049532D01*
X150942Y1049687D01*
X150597Y1049635D01*
X150252Y1049429D01*
G01X153046Y1047207D02*
X153276Y1046845D01*
X153582Y1046639D01*
X153927Y1046587D01*
X154234Y1046639D01*
X154541Y1046897D01*
X154732Y1047207D01*
X154771Y1047517D01*
X154694Y1047879D01*
X154426Y1048137D01*
X154157Y1048240D01*
X153812D01*
G01X154157D02*
X154387Y1048395D01*
X154579Y1048654D01*
X154656Y1048964D01*
X154579Y1049274D01*
X154387Y1049532D01*
X154042Y1049687D01*
X153697Y1049635D01*
X153352Y1049429D01*
G01X162648Y1024545D02*
Y1027645D01*
X163607D01*
X163913Y1027490D01*
X164105Y1027283D01*
X164182Y1026870D01*
X164105Y1026457D01*
X163875Y1026198D01*
X163607Y1026043D01*
X162648D01*
G01X163607D02*
X164182Y1024545D01*
G01X166515D02*
Y1027645D01*
X166055Y1027025D01*
G01Y1024545D02*
X166975D01*
G01X169615Y1027645D02*
X169308Y1027542D01*
X169078Y1027283D01*
X168925Y1026973D01*
X168810Y1026560D01*
X168772Y1026095D01*
X168810Y1025630D01*
X168925Y1025217D01*
X169078Y1024907D01*
X169308Y1024648D01*
X169615Y1024545D01*
X169922Y1024648D01*
X170152Y1024907D01*
X170305Y1025217D01*
X170420Y1025630D01*
X170458Y1026095D01*
X170420Y1026560D01*
X170305Y1026973D01*
X170152Y1027283D01*
X169922Y1027542D01*
X169615Y1027645D01*
G01X171872Y1025165D02*
X172102Y1024803D01*
X172408Y1024597D01*
X172753Y1024545D01*
X173060Y1024597D01*
X173367Y1024855D01*
X173558Y1025165D01*
X173597Y1025475D01*
X173520Y1025837D01*
X173252Y1026095D01*
X172983Y1026198D01*
X172638D01*
G01X172983D02*
X173213Y1026353D01*
X173405Y1026612D01*
X173482Y1026922D01*
X173405Y1027232D01*
X173213Y1027490D01*
X172868Y1027645D01*
X172523Y1027593D01*
X172178Y1027387D01*
G01X163035Y1029441D02*
Y1032541D01*
X163994D01*
X164300Y1032386D01*
X164492Y1032179D01*
X164569Y1031766D01*
X164492Y1031353D01*
X164262Y1031094D01*
X163994Y1030939D01*
X163035D01*
G01X163994D02*
X164569Y1029441D01*
G01X166902D02*
Y1032541D01*
X166442Y1031921D01*
G01Y1029441D02*
X167362D01*
G01X170002Y1032541D02*
X169695Y1032438D01*
X169465Y1032179D01*
X169312Y1031869D01*
X169197Y1031456D01*
X169159Y1030991D01*
X169197Y1030526D01*
X169312Y1030113D01*
X169465Y1029803D01*
X169695Y1029544D01*
X170002Y1029441D01*
X170309Y1029544D01*
X170539Y1029803D01*
X170692Y1030113D01*
X170807Y1030526D01*
X170845Y1030991D01*
X170807Y1031456D01*
X170692Y1031869D01*
X170539Y1032179D01*
X170309Y1032438D01*
X170002Y1032541D01*
G01X173562Y1029441D02*
Y1032541D01*
X172144Y1030319D01*
X174060D01*
G01X168472Y1044649D02*
Y1047749D01*
X169392D01*
X169699Y1047594D01*
X169929Y1047232D01*
X170006Y1046819D01*
X169929Y1046406D01*
X169737Y1046096D01*
X169392Y1045941D01*
X168472D01*
G01X171496Y1045269D02*
X171726Y1044907D01*
X172032Y1044701D01*
X172377Y1044649D01*
X172684Y1044701D01*
X172991Y1044959D01*
X173182Y1045269D01*
X173221Y1045579D01*
X173144Y1045941D01*
X172876Y1046199D01*
X172607Y1046302D01*
X172262D01*
G01X172607D02*
X172837Y1046457D01*
X173029Y1046716D01*
X173106Y1047026D01*
X173029Y1047336D01*
X172837Y1047594D01*
X172492Y1047749D01*
X172147Y1047697D01*
X171802Y1047491D01*
G01X174711Y1047232D02*
X174941Y1047542D01*
X175209Y1047697D01*
X175516Y1047749D01*
X175899Y1047646D01*
X176167Y1047387D01*
X176244Y1047077D01*
X176206Y1046767D01*
X176052Y1046509D01*
X175286Y1045992D01*
X174941Y1045631D01*
X174711Y1045114D01*
X174634Y1044649D01*
X176244D01*
G01X169157Y1111160D02*
X166057D01*
Y1112119D01*
X166212Y1112425D01*
X166419Y1112617D01*
X166832Y1112694D01*
X167245Y1112617D01*
X167504Y1112387D01*
X167659Y1112119D01*
Y1111160D01*
G01Y1112119D02*
X169157Y1112694D01*
G01Y1115027D02*
X166057D01*
X166677Y1114567D01*
G01X169157D02*
Y1115487D01*
G01X167865Y1117399D02*
X167504Y1117667D01*
X167297Y1117897D01*
X167194Y1118204D01*
X167297Y1118472D01*
X167504Y1118664D01*
X167814Y1118817D01*
X168175Y1118855D01*
X168485Y1118817D01*
X168795Y1118664D01*
X169054Y1118434D01*
X169157Y1118165D01*
X169054Y1117859D01*
X168744Y1117590D01*
X168279Y1117437D01*
X167762Y1117399D01*
X167090Y1117475D01*
X166729Y1117590D01*
X166367Y1117782D01*
X166109Y1118050D01*
X166057Y1118319D01*
X166160Y1118587D01*
X166419Y1118779D01*
G01X157717Y1117652D02*
Y1111452D01*
X154517D01*
Y1117652D01*
X157717D01*
G01X164462Y1105229D02*
Y1108329D01*
X165421D01*
X165727Y1108174D01*
X165919Y1107967D01*
X165996Y1107554D01*
X165919Y1107141D01*
X165689Y1106882D01*
X165421Y1106727D01*
X164462D01*
G01X165421D02*
X165996Y1105229D01*
G01X167601Y1107812D02*
X167831Y1108122D01*
X168099Y1108277D01*
X168406Y1108329D01*
X168789Y1108226D01*
X169057Y1107967D01*
X169134Y1107657D01*
X169096Y1107347D01*
X168942Y1107089D01*
X168176Y1106572D01*
X167831Y1106211D01*
X167601Y1105694D01*
X167524Y1105229D01*
X169134D01*
G01X170586Y1105694D02*
X170816Y1105436D01*
X171084Y1105281D01*
X171429Y1105229D01*
X171774Y1105332D01*
X172042Y1105539D01*
X172234Y1105901D01*
X172272Y1106314D01*
X172196Y1106727D01*
X172004Y1106986D01*
X171736Y1107192D01*
X171467Y1107244D01*
X171199Y1107192D01*
X170854Y1106986D01*
X170969Y1108329D01*
X172004D01*
G01X160803Y1105253D02*
X154603D01*
Y1108453D01*
X160803D01*
Y1105253D01*
G01X162470Y1117660D02*
Y1111460D01*
X159270D01*
Y1117660D01*
X162470D01*
G01X163205Y1118928D02*
X160105D01*
Y1119887D01*
X160260Y1120193D01*
X160467Y1120385D01*
X160880Y1120462D01*
X161293Y1120385D01*
X161552Y1120155D01*
X161707Y1119887D01*
Y1118928D01*
G01Y1119887D02*
X163205Y1120462D01*
G01Y1122795D02*
X160105D01*
X160725Y1122335D01*
G01X163205D02*
Y1123255D01*
G01X160622Y1125167D02*
X160312Y1125397D01*
X160157Y1125665D01*
X160105Y1125972D01*
X160208Y1126355D01*
X160467Y1126623D01*
X160777Y1126700D01*
X161087Y1126662D01*
X161345Y1126508D01*
X161862Y1125742D01*
X162223Y1125397D01*
X162740Y1125167D01*
X163205Y1125090D01*
Y1126700D01*
G01X160622Y1128267D02*
X160312Y1128497D01*
X160157Y1128765D01*
X160105Y1129072D01*
X160208Y1129455D01*
X160467Y1129723D01*
X160777Y1129800D01*
X161087Y1129762D01*
X161345Y1129608D01*
X161862Y1128842D01*
X162223Y1128497D01*
X162740Y1128267D01*
X163205Y1128190D01*
Y1129800D01*
G01X161796Y1131030D02*
Y1134130D01*
X162755D01*
X163061Y1133975D01*
X163253Y1133768D01*
X163330Y1133355D01*
X163253Y1132942D01*
X163023Y1132683D01*
X162755Y1132528D01*
X161796D01*
G01X162755D02*
X163330Y1131030D01*
G01X165663D02*
Y1134130D01*
X165203Y1133510D01*
G01Y1131030D02*
X166123D01*
G01X167920Y1131495D02*
X168150Y1131237D01*
X168418Y1131082D01*
X168763Y1131030D01*
X169108Y1131133D01*
X169376Y1131340D01*
X169568Y1131702D01*
X169606Y1132115D01*
X169530Y1132528D01*
X169338Y1132787D01*
X169070Y1132993D01*
X168801Y1133045D01*
X168533Y1132993D01*
X168188Y1132787D01*
X168303Y1134130D01*
X169338D01*
G01X160022Y1130578D02*
X153822D01*
Y1133778D01*
X160022D01*
Y1130578D01*
G01X156662Y1138751D02*
X153562D01*
Y1139710D01*
X153717Y1140016D01*
X153924Y1140208D01*
X154337Y1140285D01*
X154750Y1140208D01*
X155009Y1139978D01*
X155164Y1139710D01*
Y1138751D01*
G01Y1139710D02*
X156662Y1140285D01*
G01Y1142618D02*
X153562D01*
X154182Y1142158D01*
G01X156662D02*
Y1143078D01*
G01X153562Y1145718D02*
X153665Y1145411D01*
X153924Y1145181D01*
X154234Y1145028D01*
X154647Y1144913D01*
X155112Y1144875D01*
X155577Y1144913D01*
X155990Y1145028D01*
X156300Y1145181D01*
X156559Y1145411D01*
X156662Y1145718D01*
X156559Y1146025D01*
X156300Y1146255D01*
X155990Y1146408D01*
X155577Y1146523D01*
X155112Y1146561D01*
X154647Y1146523D01*
X154234Y1146408D01*
X153924Y1146255D01*
X153665Y1146025D01*
X153562Y1145718D01*
G01X155370Y1148090D02*
X155009Y1148358D01*
X154802Y1148588D01*
X154699Y1148895D01*
X154802Y1149163D01*
X155009Y1149355D01*
X155319Y1149508D01*
X155680Y1149546D01*
X155990Y1149508D01*
X156300Y1149355D01*
X156559Y1149125D01*
X156662Y1148856D01*
X156559Y1148550D01*
X156249Y1148281D01*
X155784Y1148128D01*
X155267Y1148090D01*
X154595Y1148166D01*
X154234Y1148281D01*
X153872Y1148473D01*
X153614Y1148741D01*
X153562Y1149010D01*
X153665Y1149278D01*
X153924Y1149470D01*
G01X156864Y1136869D02*
Y1130669D01*
X153664D01*
Y1136869D01*
X156864D01*
G01X153663Y1127520D02*
Y1133720D01*
X156863D01*
Y1127520D01*
X153663D01*
G01X168613Y1215637D02*
X168383Y1215792D01*
X168115Y1215895D01*
X167808D01*
X167463Y1215740D01*
X167195Y1215482D01*
X167003Y1215172D01*
X166850Y1214655D01*
X166812Y1214190D01*
X166888Y1213725D01*
X167003Y1213415D01*
X167233Y1213105D01*
X167502Y1212898D01*
X167770Y1212795D01*
X168038D01*
X168307Y1212898D01*
X168537Y1213053D01*
X168728Y1213260D01*
G01X171637Y1212795D02*
X170103D01*
Y1215895D01*
X171637D01*
G01X171023Y1214397D02*
X170103D01*
G01X173970Y1212795D02*
Y1215895D01*
X173510Y1215275D01*
G01Y1212795D02*
X174430D01*
G01X177530D02*
Y1215895D01*
X176112Y1213673D01*
X178028D01*
G01X168868Y1220297D02*
Y1223397D01*
X169788D01*
X170095Y1223242D01*
X170325Y1222880D01*
X170402Y1222467D01*
X170325Y1222054D01*
X170133Y1221744D01*
X169788Y1221589D01*
X168868D01*
G01X171892Y1220917D02*
X172122Y1220555D01*
X172428Y1220349D01*
X172773Y1220297D01*
X173080Y1220349D01*
X173387Y1220607D01*
X173578Y1220917D01*
X173617Y1221227D01*
X173540Y1221589D01*
X173272Y1221847D01*
X173003Y1221950D01*
X172658D01*
G01X173003D02*
X173233Y1222105D01*
X173425Y1222364D01*
X173502Y1222674D01*
X173425Y1222984D01*
X173233Y1223242D01*
X172888Y1223397D01*
X172543Y1223345D01*
X172198Y1223139D01*
G01X175107Y1222880D02*
X175337Y1223190D01*
X175605Y1223345D01*
X175912Y1223397D01*
X176295Y1223294D01*
X176563Y1223035D01*
X176640Y1222725D01*
X176602Y1222415D01*
X176448Y1222157D01*
X175682Y1221640D01*
X175337Y1221279D01*
X175107Y1220762D01*
X175030Y1220297D01*
X176640D01*
G01X151613Y1323252D02*
X151805Y1322942D01*
X152035Y1322735D01*
X152303Y1322632D01*
X152610Y1322735D01*
X152840Y1322942D01*
X153070Y1323252D01*
X153147Y1323665D01*
Y1325732D01*
G01X155940Y1322632D02*
Y1325732D01*
X154522Y1323510D01*
X156438D01*
G01X150274Y1372812D02*
X150542Y1373173D01*
X150772Y1373380D01*
X151079Y1373483D01*
X151347Y1373380D01*
X151539Y1373173D01*
X151692Y1372863D01*
X151730Y1372502D01*
X151692Y1372192D01*
X151539Y1371882D01*
X151309Y1371623D01*
X151040Y1371520D01*
X150734Y1371623D01*
X150465Y1371933D01*
X150312Y1372398D01*
X150274Y1372915D01*
X150350Y1373587D01*
X150465Y1373948D01*
X150657Y1374310D01*
X150925Y1374568D01*
X151194Y1374620D01*
X151462Y1374517D01*
X151654Y1374258D01*
G01X154562Y1371520D02*
Y1374620D01*
X153144Y1372398D01*
X155060D01*
G01X150343Y1397243D02*
X150573Y1396881D01*
X150879Y1396675D01*
X151224Y1396623D01*
X151531Y1396675D01*
X151838Y1396933D01*
X152029Y1397243D01*
X152068Y1397553D01*
X151991Y1397915D01*
X151723Y1398173D01*
X151454Y1398276D01*
X151109D01*
G01X151454D02*
X151684Y1398431D01*
X151876Y1398690D01*
X151953Y1399000D01*
X151876Y1399310D01*
X151684Y1399568D01*
X151339Y1399723D01*
X150994Y1399671D01*
X150649Y1399465D01*
G01X153443Y1397243D02*
X153673Y1396881D01*
X153979Y1396675D01*
X154324Y1396623D01*
X154631Y1396675D01*
X154938Y1396933D01*
X155129Y1397243D01*
X155168Y1397553D01*
X155091Y1397915D01*
X154823Y1398173D01*
X154554Y1398276D01*
X154209D01*
G01X154554D02*
X154784Y1398431D01*
X154976Y1398690D01*
X155053Y1399000D01*
X154976Y1399310D01*
X154784Y1399568D01*
X154439Y1399723D01*
X154094Y1399671D01*
X153749Y1399465D01*
G01X170053Y1395675D02*
Y1398775D01*
X170973D01*
X171280Y1398620D01*
X171510Y1398258D01*
X171587Y1397845D01*
X171510Y1397432D01*
X171318Y1397122D01*
X170973Y1396967D01*
X170053D01*
G01X173077Y1396295D02*
X173307Y1395933D01*
X173613Y1395727D01*
X173958Y1395675D01*
X174265Y1395727D01*
X174572Y1395985D01*
X174763Y1396295D01*
X174802Y1396605D01*
X174725Y1396967D01*
X174457Y1397225D01*
X174188Y1397328D01*
X173843D01*
G01X174188D02*
X174418Y1397483D01*
X174610Y1397742D01*
X174687Y1398052D01*
X174610Y1398362D01*
X174418Y1398620D01*
X174073Y1398775D01*
X173728Y1398723D01*
X173383Y1398517D01*
G01X176292Y1398258D02*
X176522Y1398568D01*
X176790Y1398723D01*
X177097Y1398775D01*
X177480Y1398672D01*
X177748Y1398413D01*
X177825Y1398103D01*
X177787Y1397793D01*
X177633Y1397535D01*
X176867Y1397018D01*
X176522Y1396657D01*
X176292Y1396140D01*
X176215Y1395675D01*
X177825D01*
G01X166397Y1455646D02*
Y1458746D01*
X167356D01*
X167662Y1458591D01*
X167854Y1458384D01*
X167931Y1457971D01*
X167854Y1457558D01*
X167624Y1457299D01*
X167356Y1457144D01*
X166397D01*
G01X167356D02*
X167931Y1455646D01*
G01X169536Y1458229D02*
X169766Y1458539D01*
X170034Y1458694D01*
X170341Y1458746D01*
X170724Y1458643D01*
X170992Y1458384D01*
X171069Y1458074D01*
X171031Y1457764D01*
X170877Y1457506D01*
X170111Y1456989D01*
X169766Y1456628D01*
X169536Y1456111D01*
X169459Y1455646D01*
X171069D01*
G01X173824D02*
Y1458746D01*
X172406Y1456524D01*
X174322D01*
G01X161777Y1455484D02*
X155577D01*
Y1458684D01*
X161777D01*
Y1455484D01*
G01X165787Y1478921D02*
Y1482021D01*
X166746D01*
X167052Y1481866D01*
X167244Y1481659D01*
X167321Y1481246D01*
X167244Y1480833D01*
X167014Y1480574D01*
X166746Y1480419D01*
X165787D01*
G01X166746D02*
X167321Y1478921D01*
G01X169654D02*
Y1482021D01*
X169194Y1481401D01*
G01Y1478921D02*
X170114D01*
G01X173214D02*
Y1482021D01*
X171796Y1479799D01*
X173712D01*
G01X160501Y1478669D02*
X154301D01*
Y1481869D01*
X160501D01*
Y1478669D01*
G01X165230Y1459883D02*
Y1462983D01*
X166189D01*
X166495Y1462828D01*
X166687Y1462621D01*
X166764Y1462208D01*
X166687Y1461795D01*
X166457Y1461536D01*
X166189Y1461381D01*
X165230D01*
G01X166189D02*
X166764Y1459883D01*
G01X168369Y1462466D02*
X168599Y1462776D01*
X168867Y1462931D01*
X169174Y1462983D01*
X169557Y1462880D01*
X169825Y1462621D01*
X169902Y1462311D01*
X169864Y1462001D01*
X169710Y1461743D01*
X168944Y1461226D01*
X168599Y1460865D01*
X168369Y1460348D01*
X168292Y1459883D01*
X169902D01*
G01X172120D02*
X172197Y1460555D01*
X172312Y1461123D01*
X172465Y1461640D01*
X172657Y1462208D01*
X172964Y1462983D01*
X171430D01*
G01X161030Y1461051D02*
X154830D01*
Y1464251D01*
X161030D01*
Y1461051D01*
G01X165524Y1470028D02*
Y1473128D01*
X166483D01*
X166789Y1472973D01*
X166981Y1472766D01*
X167058Y1472353D01*
X166981Y1471940D01*
X166751Y1471681D01*
X166483Y1471526D01*
X165524D01*
G01X166483D02*
X167058Y1470028D01*
G01X169851D02*
Y1473128D01*
X168433Y1470906D01*
X170349D01*
G01X172951Y1470028D02*
Y1473128D01*
X171533Y1470906D01*
X173449D01*
G01X154123Y1474620D02*
X160323D01*
Y1471420D01*
X154123D01*
Y1474620D01*
G01X157434Y1484949D02*
Y1478749D01*
X154234D01*
Y1484949D01*
X157434D01*
G01X166018Y1474410D02*
Y1477510D01*
X166977D01*
X167283Y1477355D01*
X167475Y1477148D01*
X167552Y1476735D01*
X167475Y1476322D01*
X167245Y1476063D01*
X166977Y1475908D01*
X166018D01*
G01X166977D02*
X167552Y1474410D01*
G01X169885D02*
Y1477510D01*
X169425Y1476890D01*
G01Y1474410D02*
X170345D01*
G01X172257Y1476993D02*
X172487Y1477303D01*
X172755Y1477458D01*
X173062Y1477510D01*
X173445Y1477407D01*
X173713Y1477148D01*
X173790Y1476838D01*
X173752Y1476528D01*
X173598Y1476270D01*
X172832Y1475753D01*
X172487Y1475392D01*
X172257Y1474875D01*
X172180Y1474410D01*
X173790D01*
G01X175357Y1475702D02*
X175625Y1476063D01*
X175855Y1476270D01*
X176162Y1476373D01*
X176430Y1476270D01*
X176622Y1476063D01*
X176775Y1475753D01*
X176813Y1475392D01*
X176775Y1475082D01*
X176622Y1474772D01*
X176392Y1474513D01*
X176123Y1474410D01*
X175817Y1474513D01*
X175548Y1474823D01*
X175395Y1475288D01*
X175357Y1475805D01*
X175433Y1476477D01*
X175548Y1476838D01*
X175740Y1477200D01*
X176008Y1477458D01*
X176277Y1477510D01*
X176545Y1477407D01*
X176737Y1477148D01*
G01X154216Y1475599D02*
Y1481799D01*
X157416D01*
Y1475599D01*
X154216D01*
G01X157886Y1485755D02*
X154786D01*
Y1486714D01*
X154941Y1487020D01*
X155148Y1487212D01*
X155561Y1487289D01*
X155974Y1487212D01*
X156233Y1486982D01*
X156388Y1486714D01*
Y1485755D01*
G01Y1486714D02*
X157886Y1487289D01*
G01Y1489622D02*
X154786D01*
X155406Y1489162D01*
G01X157886D02*
Y1490082D01*
G01X154786Y1492722D02*
X154889Y1492415D01*
X155148Y1492185D01*
X155458Y1492032D01*
X155871Y1491917D01*
X156336Y1491879D01*
X156801Y1491917D01*
X157214Y1492032D01*
X157524Y1492185D01*
X157783Y1492415D01*
X157886Y1492722D01*
X157783Y1493029D01*
X157524Y1493259D01*
X157214Y1493412D01*
X156801Y1493527D01*
X156336Y1493565D01*
X155871Y1493527D01*
X155458Y1493412D01*
X155148Y1493259D01*
X154889Y1493029D01*
X154786Y1492722D01*
G01X155303Y1495094D02*
X154993Y1495324D01*
X154838Y1495592D01*
X154786Y1495899D01*
X154889Y1496282D01*
X155148Y1496550D01*
X155458Y1496627D01*
X155768Y1496589D01*
X156026Y1496435D01*
X156543Y1495669D01*
X156904Y1495324D01*
X157421Y1495094D01*
X157886Y1495017D01*
Y1496627D01*
G01X169525Y1571461D02*
Y1574561D01*
X170445D01*
X170752Y1574406D01*
X170982Y1574044D01*
X171059Y1573631D01*
X170982Y1573218D01*
X170790Y1572908D01*
X170445Y1572753D01*
X169525D01*
G01X172549Y1572081D02*
X172779Y1571719D01*
X173085Y1571513D01*
X173430Y1571461D01*
X173737Y1571513D01*
X174044Y1571771D01*
X174235Y1572081D01*
X174274Y1572391D01*
X174197Y1572753D01*
X173929Y1573011D01*
X173660Y1573114D01*
X173315D01*
G01X173660D02*
X173890Y1573269D01*
X174082Y1573528D01*
X174159Y1573838D01*
X174082Y1574148D01*
X173890Y1574406D01*
X173545Y1574561D01*
X173200Y1574509D01*
X172855Y1574303D01*
G01X175764Y1574044D02*
X175994Y1574354D01*
X176262Y1574509D01*
X176569Y1574561D01*
X176952Y1574458D01*
X177220Y1574199D01*
X177297Y1573889D01*
X177259Y1573579D01*
X177105Y1573321D01*
X176339Y1572804D01*
X175994Y1572443D01*
X175764Y1571926D01*
X175687Y1571461D01*
X177297D01*
G01X150939Y1721106D02*
X151207Y1721467D01*
X151437Y1721674D01*
X151744Y1721777D01*
X152012Y1721674D01*
X152204Y1721467D01*
X152357Y1721157D01*
X152395Y1720796D01*
X152357Y1720486D01*
X152204Y1720176D01*
X151974Y1719917D01*
X151705Y1719814D01*
X151399Y1719917D01*
X151130Y1720227D01*
X150977Y1720692D01*
X150939Y1721209D01*
X151015Y1721881D01*
X151130Y1722242D01*
X151322Y1722604D01*
X151590Y1722862D01*
X151859Y1722914D01*
X152127Y1722811D01*
X152319Y1722552D01*
G01X155227Y1719814D02*
Y1722914D01*
X153809Y1720692D01*
X155725D01*
G01X150942Y1747011D02*
X151172Y1746649D01*
X151478Y1746443D01*
X151823Y1746391D01*
X152130Y1746443D01*
X152437Y1746701D01*
X152628Y1747011D01*
X152667Y1747321D01*
X152590Y1747683D01*
X152322Y1747941D01*
X152053Y1748044D01*
X151708D01*
G01X152053D02*
X152283Y1748199D01*
X152475Y1748458D01*
X152552Y1748768D01*
X152475Y1749078D01*
X152283Y1749336D01*
X151938Y1749491D01*
X151593Y1749439D01*
X151248Y1749233D01*
G01X154042Y1747011D02*
X154272Y1746649D01*
X154578Y1746443D01*
X154923Y1746391D01*
X155230Y1746443D01*
X155537Y1746701D01*
X155728Y1747011D01*
X155767Y1747321D01*
X155690Y1747683D01*
X155422Y1747941D01*
X155153Y1748044D01*
X154808D01*
G01X155153D02*
X155383Y1748199D01*
X155575Y1748458D01*
X155652Y1748768D01*
X155575Y1749078D01*
X155383Y1749336D01*
X155038Y1749491D01*
X154693Y1749439D01*
X154348Y1749233D01*
G01X169418Y1764601D02*
Y1767701D01*
X170338D01*
X170645Y1767546D01*
X170875Y1767184D01*
X170952Y1766771D01*
X170875Y1766358D01*
X170683Y1766048D01*
X170338Y1765893D01*
X169418D01*
G01X172442Y1765221D02*
X172672Y1764859D01*
X172978Y1764653D01*
X173323Y1764601D01*
X173630Y1764653D01*
X173937Y1764911D01*
X174128Y1765221D01*
X174167Y1765531D01*
X174090Y1765893D01*
X173822Y1766151D01*
X173553Y1766254D01*
X173208D01*
G01X173553D02*
X173783Y1766409D01*
X173975Y1766668D01*
X174052Y1766978D01*
X173975Y1767288D01*
X173783Y1767546D01*
X173438Y1767701D01*
X173093Y1767649D01*
X172748Y1767443D01*
G01X175657Y1767184D02*
X175887Y1767494D01*
X176155Y1767649D01*
X176462Y1767701D01*
X176845Y1767598D01*
X177113Y1767339D01*
X177190Y1767029D01*
X177152Y1766719D01*
X176998Y1766461D01*
X176232Y1765944D01*
X175887Y1765583D01*
X175657Y1765066D01*
X175580Y1764601D01*
X177190D01*
G01X161863Y1818441D02*
Y1821541D01*
X162822D01*
X163128Y1821386D01*
X163320Y1821179D01*
X163397Y1820766D01*
X163320Y1820353D01*
X163090Y1820094D01*
X162822Y1819939D01*
X161863D01*
G01X162822D02*
X163397Y1818441D01*
G01X165730D02*
Y1821541D01*
X165270Y1820921D01*
G01Y1818441D02*
X166190D01*
G01X168830D02*
X169098Y1818493D01*
X169405Y1818648D01*
X169597Y1818906D01*
X169673Y1819268D01*
X169597Y1819629D01*
X169367Y1819939D01*
X169022Y1820094D01*
X168638D01*
X168408Y1820198D01*
X168217Y1820456D01*
X168140Y1820818D01*
X168255Y1821179D01*
X168523Y1821438D01*
X168830Y1821541D01*
X169137Y1821438D01*
X169405Y1821179D01*
X169520Y1820818D01*
X169443Y1820456D01*
X169252Y1820198D01*
X169022Y1820094D01*
X168638D01*
X168293Y1819939D01*
X168063Y1819629D01*
X167987Y1819268D01*
X168063Y1818906D01*
X168255Y1818648D01*
X168562Y1818493D01*
X168830Y1818441D01*
G01X153884Y1821960D02*
X160084D01*
Y1818760D01*
X153884D01*
Y1821960D01*
G01X164697Y1805686D02*
Y1808786D01*
X165656D01*
X165962Y1808631D01*
X166154Y1808424D01*
X166231Y1808011D01*
X166154Y1807598D01*
X165924Y1807339D01*
X165656Y1807184D01*
X164697D01*
G01X165656D02*
X166231Y1805686D01*
G01X167836Y1808269D02*
X168066Y1808579D01*
X168334Y1808734D01*
X168641Y1808786D01*
X169024Y1808683D01*
X169292Y1808424D01*
X169369Y1808114D01*
X169331Y1807804D01*
X169177Y1807546D01*
X168411Y1807029D01*
X168066Y1806668D01*
X167836Y1806151D01*
X167759Y1805686D01*
X169369D01*
G01X170936Y1806978D02*
X171204Y1807339D01*
X171434Y1807546D01*
X171741Y1807649D01*
X172009Y1807546D01*
X172201Y1807339D01*
X172354Y1807029D01*
X172392Y1806668D01*
X172354Y1806358D01*
X172201Y1806048D01*
X171971Y1805789D01*
X171702Y1805686D01*
X171396Y1805789D01*
X171127Y1806099D01*
X170974Y1806564D01*
X170936Y1807081D01*
X171012Y1807753D01*
X171127Y1808114D01*
X171319Y1808476D01*
X171587Y1808734D01*
X171856Y1808786D01*
X172124Y1808683D01*
X172316Y1808424D01*
G01X160365Y1806140D02*
X154165D01*
Y1809340D01*
X160365D01*
Y1806140D01*
G01X165178Y1813334D02*
Y1816434D01*
X166137D01*
X166443Y1816279D01*
X166635Y1816072D01*
X166712Y1815659D01*
X166635Y1815246D01*
X166405Y1814987D01*
X166137Y1814832D01*
X165178D01*
G01X166137D02*
X166712Y1813334D01*
G01X168317Y1815917D02*
X168547Y1816227D01*
X168815Y1816382D01*
X169122Y1816434D01*
X169505Y1816331D01*
X169773Y1816072D01*
X169850Y1815762D01*
X169812Y1815452D01*
X169658Y1815194D01*
X168892Y1814677D01*
X168547Y1814316D01*
X168317Y1813799D01*
X168240Y1813334D01*
X169850D01*
G01X171302Y1813954D02*
X171532Y1813592D01*
X171838Y1813386D01*
X172183Y1813334D01*
X172490Y1813386D01*
X172797Y1813644D01*
X172988Y1813954D01*
X173027Y1814264D01*
X172950Y1814626D01*
X172682Y1814884D01*
X172413Y1814987D01*
X172068D01*
G01X172413D02*
X172643Y1815142D01*
X172835Y1815401D01*
X172912Y1815711D01*
X172835Y1816021D01*
X172643Y1816279D01*
X172298Y1816434D01*
X171953Y1816382D01*
X171608Y1816176D01*
G01X160088Y1814031D02*
X153888D01*
Y1817231D01*
X160088D01*
Y1814031D01*
G01X164305Y1827486D02*
Y1830586D01*
X165264D01*
X165570Y1830431D01*
X165762Y1830224D01*
X165839Y1829811D01*
X165762Y1829398D01*
X165532Y1829139D01*
X165264Y1828984D01*
X164305D01*
G01X165264D02*
X165839Y1827486D01*
G01X168172D02*
Y1830586D01*
X167712Y1829966D01*
G01Y1827486D02*
X168632D01*
G01X171195D02*
X171272Y1828158D01*
X171387Y1828726D01*
X171540Y1829243D01*
X171732Y1829811D01*
X172039Y1830586D01*
X170505D01*
G01X160331Y1826625D02*
X154131D01*
Y1829825D01*
X160331D01*
Y1826625D01*
G01X157447Y1834744D02*
X154347D01*
Y1835703D01*
X154502Y1836009D01*
X154709Y1836201D01*
X155122Y1836278D01*
X155535Y1836201D01*
X155794Y1835971D01*
X155949Y1835703D01*
Y1834744D01*
G01Y1835703D02*
X157447Y1836278D01*
G01X157085Y1837959D02*
X157344Y1838228D01*
X157447Y1838534D01*
X157344Y1838841D01*
X157034Y1839109D01*
X156569Y1839301D01*
X156104Y1839378D01*
X155535D01*
X155070Y1839301D01*
X154657Y1839109D01*
X154450Y1838879D01*
X154347Y1838611D01*
X154450Y1838304D01*
X154657Y1838074D01*
X154967Y1837921D01*
X155380Y1837844D01*
X155742Y1837921D01*
X156104Y1838113D01*
X156310Y1838343D01*
X156362Y1838611D01*
X156259Y1838918D01*
X156000Y1839148D01*
X155535Y1839378D01*
G01X157447Y1841711D02*
X157395Y1841979D01*
X157240Y1842286D01*
X156982Y1842478D01*
X156620Y1842554D01*
X156259Y1842478D01*
X155949Y1842248D01*
X155794Y1841903D01*
Y1841519D01*
X155690Y1841289D01*
X155432Y1841098D01*
X155070Y1841021D01*
X154709Y1841136D01*
X154450Y1841404D01*
X154347Y1841711D01*
X154450Y1842018D01*
X154709Y1842286D01*
X155070Y1842401D01*
X155432Y1842324D01*
X155690Y1842133D01*
X155794Y1841903D01*
Y1841519D01*
X155949Y1841174D01*
X156259Y1840944D01*
X156620Y1840868D01*
X156982Y1840944D01*
X157240Y1841136D01*
X157395Y1841443D01*
X157447Y1841711D01*
G01X157170Y1832905D02*
Y1826705D01*
X153970D01*
Y1832905D01*
X157170D01*
G01X163275Y1822631D02*
Y1825731D01*
X164234D01*
X164540Y1825576D01*
X164732Y1825369D01*
X164809Y1824956D01*
X164732Y1824543D01*
X164502Y1824284D01*
X164234Y1824129D01*
X163275D01*
G01X164234D02*
X164809Y1822631D01*
G01X167142D02*
Y1825731D01*
X166682Y1825111D01*
G01Y1822631D02*
X167602D01*
G01X169399Y1823251D02*
X169629Y1822889D01*
X169935Y1822683D01*
X170280Y1822631D01*
X170587Y1822683D01*
X170894Y1822941D01*
X171085Y1823251D01*
X171124Y1823561D01*
X171047Y1823923D01*
X170779Y1824181D01*
X170510Y1824284D01*
X170165D01*
G01X170510D02*
X170740Y1824439D01*
X170932Y1824698D01*
X171009Y1825008D01*
X170932Y1825318D01*
X170740Y1825576D01*
X170395Y1825731D01*
X170050Y1825679D01*
X169705Y1825473D01*
G01X173342Y1825731D02*
X173035Y1825628D01*
X172805Y1825369D01*
X172652Y1825059D01*
X172537Y1824646D01*
X172499Y1824181D01*
X172537Y1823716D01*
X172652Y1823303D01*
X172805Y1822993D01*
X173035Y1822734D01*
X173342Y1822631D01*
X173649Y1822734D01*
X173879Y1822993D01*
X174032Y1823303D01*
X174147Y1823716D01*
X174185Y1824181D01*
X174147Y1824646D01*
X174032Y1825059D01*
X173879Y1825369D01*
X173649Y1825628D01*
X173342Y1825731D01*
G01X153961Y1823562D02*
Y1829762D01*
X157161D01*
Y1823562D01*
X153961D01*
G01X168209Y1920916D02*
Y1924016D01*
X169129D01*
X169436Y1923861D01*
X169666Y1923499D01*
X169743Y1923086D01*
X169666Y1922673D01*
X169474Y1922363D01*
X169129Y1922208D01*
X168209D01*
G01X171233Y1921536D02*
X171463Y1921174D01*
X171769Y1920968D01*
X172114Y1920916D01*
X172421Y1920968D01*
X172728Y1921226D01*
X172919Y1921536D01*
X172958Y1921846D01*
X172881Y1922208D01*
X172613Y1922466D01*
X172344Y1922569D01*
X171999D01*
G01X172344D02*
X172574Y1922724D01*
X172766Y1922983D01*
X172843Y1923293D01*
X172766Y1923603D01*
X172574Y1923861D01*
X172229Y1924016D01*
X171884Y1923964D01*
X171539Y1923758D01*
G01X174448Y1923499D02*
X174678Y1923809D01*
X174946Y1923964D01*
X175253Y1924016D01*
X175636Y1923913D01*
X175904Y1923654D01*
X175981Y1923344D01*
X175943Y1923034D01*
X175789Y1922776D01*
X175023Y1922259D01*
X174678Y1921898D01*
X174448Y1921381D01*
X174371Y1920916D01*
X175981D01*
G01X154718Y2032814D02*
X155028Y2033006D01*
X155235Y2033236D01*
X155338Y2033504D01*
X155235Y2033811D01*
X155028Y2034041D01*
X154718Y2034271D01*
X154305Y2034348D01*
X152238D01*
G01X154046Y2035953D02*
X153685Y2036221D01*
X153478Y2036451D01*
X153375Y2036758D01*
X153478Y2037026D01*
X153685Y2037218D01*
X153995Y2037371D01*
X154356Y2037409D01*
X154666Y2037371D01*
X154976Y2037218D01*
X155235Y2036988D01*
X155338Y2036719D01*
X155235Y2036413D01*
X154925Y2036144D01*
X154460Y2035991D01*
X153943Y2035953D01*
X153271Y2036029D01*
X152910Y2036144D01*
X152548Y2036336D01*
X152290Y2036604D01*
X152238Y2036873D01*
X152341Y2037141D01*
X152600Y2037333D01*
G01X149964Y2069341D02*
X150232Y2069702D01*
X150462Y2069909D01*
X150769Y2070012D01*
X151037Y2069909D01*
X151229Y2069702D01*
X151382Y2069392D01*
X151420Y2069031D01*
X151382Y2068721D01*
X151229Y2068411D01*
X150999Y2068152D01*
X150730Y2068049D01*
X150424Y2068152D01*
X150155Y2068462D01*
X150002Y2068927D01*
X149964Y2069444D01*
X150040Y2070116D01*
X150155Y2070477D01*
X150347Y2070839D01*
X150615Y2071097D01*
X150884Y2071149D01*
X151152Y2071046D01*
X151344Y2070787D01*
G01X154252Y2068049D02*
Y2071149D01*
X152834Y2068927D01*
X154750D01*
G01X172654Y55758D02*
Y58858D01*
X173574D01*
X173881Y58703D01*
X174111Y58341D01*
X174188Y57928D01*
X174111Y57515D01*
X173919Y57205D01*
X173574Y57050D01*
X172654D01*
G01X176521Y55758D02*
Y58858D01*
X176061Y58238D01*
G01Y55758D02*
X176981D01*
G01X213452Y73105D02*
G03I-16800J0D01*
G01X193986Y131602D02*
X193756Y131757D01*
X193488Y131860D01*
X193181D01*
X192836Y131705D01*
X192568Y131447D01*
X192376Y131137D01*
X192223Y130620D01*
X192185Y130155D01*
X192261Y129690D01*
X192376Y129380D01*
X192606Y129070D01*
X192875Y128863D01*
X193143Y128760D01*
X193411D01*
X193680Y128863D01*
X193910Y129018D01*
X194101Y129225D01*
G01X197010Y128760D02*
X195476D01*
Y131860D01*
X197010D01*
G01X196396Y130362D02*
X195476D01*
G01X198615Y131343D02*
X198845Y131653D01*
X199113Y131808D01*
X199420Y131860D01*
X199803Y131757D01*
X200071Y131498D01*
X200148Y131188D01*
X200110Y130878D01*
X199956Y130620D01*
X199190Y130103D01*
X198845Y129742D01*
X198615Y129225D01*
X198538Y128760D01*
X200148D01*
G01X213979Y152050D02*
G03I-16800J0D01*
G01X177034Y170205D02*
Y173305D01*
X177954D01*
X178261Y173150D01*
X178491Y172788D01*
X178568Y172375D01*
X178491Y171962D01*
X178299Y171652D01*
X177954Y171497D01*
X177034D01*
G01X180134Y170205D02*
Y173305D01*
X181093D01*
X181399Y173150D01*
X181591Y172943D01*
X181668Y172530D01*
X181591Y172117D01*
X181361Y171858D01*
X181093Y171703D01*
X180134D01*
G01X181093D02*
X181668Y170205D01*
G01X184768D02*
X183234D01*
Y173305D01*
X184768D01*
G01X184154Y171807D02*
X183234D01*
G01X186296Y170618D02*
X186603Y170360D01*
X186948Y170205D01*
X187254D01*
X187561Y170360D01*
X187791Y170618D01*
X187906Y170980D01*
X187829Y171342D01*
X187638Y171652D01*
X187293Y171858D01*
X186833Y171962D01*
X186564Y172168D01*
X186449Y172530D01*
X186526Y172892D01*
X186718Y173150D01*
X186986Y173305D01*
X187254D01*
X187523Y173202D01*
X187753Y172943D01*
G01X189396Y170618D02*
X189703Y170360D01*
X190048Y170205D01*
X190354D01*
X190661Y170360D01*
X190891Y170618D01*
X191006Y170980D01*
X190929Y171342D01*
X190738Y171652D01*
X190393Y171858D01*
X189933Y171962D01*
X189664Y172168D01*
X189549Y172530D01*
X189626Y172892D01*
X189818Y173150D01*
X190086Y173305D01*
X190354D01*
X190623Y173202D01*
X190853Y172943D01*
G01X192803Y171238D02*
X193799D01*
G01X195673Y170205D02*
Y173305D01*
X197129D01*
G01X196593Y171807D02*
X195673D01*
G01X199041Y173305D02*
X199961D01*
G01X199501D02*
Y170205D01*
G01X199041D02*
X199961D01*
G01X202601Y173305D02*
Y170205D01*
G01X201719Y173305D02*
X203483D01*
G01X214047Y247568D02*
G03I-16800J0D01*
G01X171864Y232720D02*
Y235820D01*
X172784D01*
X173091Y235665D01*
X173321Y235303D01*
X173398Y234890D01*
X173321Y234477D01*
X173129Y234167D01*
X172784Y234012D01*
X171864D01*
G01X175731Y232720D02*
Y235820D01*
X175271Y235200D01*
G01Y232720D02*
X176191D01*
G01X192577Y312666D02*
X192347Y312821D01*
X192079Y312924D01*
X191772D01*
X191427Y312769D01*
X191159Y312511D01*
X190967Y312201D01*
X190814Y311684D01*
X190776Y311219D01*
X190852Y310754D01*
X190967Y310444D01*
X191197Y310134D01*
X191466Y309927D01*
X191734Y309824D01*
X192002D01*
X192271Y309927D01*
X192501Y310082D01*
X192692Y310289D01*
G01X195601Y309824D02*
X194067D01*
Y312924D01*
X195601D01*
G01X194987Y311426D02*
X194067D01*
G01X198394Y309824D02*
Y312924D01*
X196976Y310702D01*
X198892D01*
G01X214507Y331786D02*
G03I-16800J0D01*
G01X213451Y421732D02*
G03I-16800J0D01*
G01X179759Y407054D02*
Y410154D01*
X180679D01*
X180986Y409999D01*
X181216Y409637D01*
X181293Y409224D01*
X181216Y408811D01*
X181024Y408501D01*
X180679Y408346D01*
X179759D01*
G01X183626Y407054D02*
Y410154D01*
X183166Y409534D01*
G01Y407054D02*
X184086D01*
G01X214243Y506517D02*
G03I-16800J0D01*
G01X216578Y598130D02*
G03I-16800J0D01*
G01X214506Y681645D02*
G03I-16800J0D01*
G01X171108Y737301D02*
Y740401D01*
X172028D01*
X172335Y740246D01*
X172565Y739884D01*
X172642Y739471D01*
X172565Y739058D01*
X172373Y738748D01*
X172028Y738593D01*
X171108D01*
G01X174975Y737301D02*
Y740401D01*
X174515Y739781D01*
G01Y737301D02*
X175435D01*
G01X215536Y774526D02*
G03I-16800J0D01*
G01X215296Y856244D02*
G03I-16800J0D01*
G01X220001Y947202D02*
G03I-16800J0D01*
G01X185898Y936379D02*
X179698D01*
Y939579D01*
X185898D01*
Y936379D01*
G01X185809Y941979D02*
X179609D01*
Y945179D01*
X185809D01*
Y941979D01*
G01X170811Y931235D02*
Y934335D01*
X171731D01*
X172038Y934180D01*
X172268Y933818D01*
X172345Y933405D01*
X172268Y932992D01*
X172076Y932682D01*
X171731Y932527D01*
X170811D01*
G01X174678Y931235D02*
Y934335D01*
X174218Y933715D01*
G01Y931235D02*
X175138D01*
G01X185721Y961071D02*
X179521D01*
Y964271D01*
X185721D01*
Y961071D01*
G01X185810Y955471D02*
X179610D01*
Y958671D01*
X185810D01*
Y955471D01*
G01X187100Y974346D02*
Y977446D01*
X188059D01*
X188365Y977291D01*
X188557Y977084D01*
X188634Y976671D01*
X188557Y976258D01*
X188327Y975999D01*
X188059Y975844D01*
X187100D01*
G01X188059D02*
X188634Y974346D01*
G01X190315Y974708D02*
X190584Y974449D01*
X190890Y974346D01*
X191197Y974449D01*
X191465Y974759D01*
X191657Y975224D01*
X191734Y975689D01*
Y976258D01*
X191657Y976723D01*
X191465Y977136D01*
X191235Y977343D01*
X190967Y977446D01*
X190660Y977343D01*
X190430Y977136D01*
X190277Y976826D01*
X190200Y976413D01*
X190277Y976051D01*
X190469Y975689D01*
X190699Y975483D01*
X190967Y975431D01*
X191274Y975534D01*
X191504Y975793D01*
X191734Y976258D01*
G01X193224Y974811D02*
X193454Y974553D01*
X193722Y974398D01*
X194067Y974346D01*
X194412Y974449D01*
X194680Y974656D01*
X194872Y975018D01*
X194910Y975431D01*
X194834Y975844D01*
X194642Y976103D01*
X194374Y976309D01*
X194105Y976361D01*
X193837Y976309D01*
X193492Y976103D01*
X193607Y977446D01*
X194642D01*
G01X187206Y970014D02*
Y973114D01*
X188165D01*
X188471Y972959D01*
X188663Y972752D01*
X188740Y972339D01*
X188663Y971926D01*
X188433Y971667D01*
X188165Y971512D01*
X187206D01*
G01X188165D02*
X188740Y970014D01*
G01X190421Y970376D02*
X190690Y970117D01*
X190996Y970014D01*
X191303Y970117D01*
X191571Y970427D01*
X191763Y970892D01*
X191840Y971357D01*
Y971926D01*
X191763Y972391D01*
X191571Y972804D01*
X191341Y973011D01*
X191073Y973114D01*
X190766Y973011D01*
X190536Y972804D01*
X190383Y972494D01*
X190306Y972081D01*
X190383Y971719D01*
X190575Y971357D01*
X190805Y971151D01*
X191073Y971099D01*
X191380Y971202D01*
X191610Y971461D01*
X191840Y971926D01*
G01X193445Y971306D02*
X193713Y971667D01*
X193943Y971874D01*
X194250Y971977D01*
X194518Y971874D01*
X194710Y971667D01*
X194863Y971357D01*
X194901Y970996D01*
X194863Y970686D01*
X194710Y970376D01*
X194480Y970117D01*
X194211Y970014D01*
X193905Y970117D01*
X193636Y970427D01*
X193483Y970892D01*
X193445Y971409D01*
X193521Y972081D01*
X193636Y972442D01*
X193828Y972804D01*
X194096Y973062D01*
X194365Y973114D01*
X194633Y973011D01*
X194825Y972752D01*
G01X186064Y971954D02*
X179864D01*
Y975154D01*
X186064D01*
Y971954D01*
G01X173483Y984476D02*
Y987576D01*
X174442D01*
X174748Y987421D01*
X174940Y987214D01*
X175017Y986801D01*
X174940Y986388D01*
X174710Y986129D01*
X174442Y985974D01*
X173483D01*
G01X174442D02*
X175017Y984476D01*
G01X177350D02*
Y987576D01*
X176890Y986956D01*
G01Y984476D02*
X177810D01*
G01X180450Y987576D02*
X180143Y987473D01*
X179913Y987214D01*
X179760Y986904D01*
X179645Y986491D01*
X179607Y986026D01*
X179645Y985561D01*
X179760Y985148D01*
X179913Y984838D01*
X180143Y984579D01*
X180450Y984476D01*
X180757Y984579D01*
X180987Y984838D01*
X181140Y985148D01*
X181255Y985561D01*
X181293Y986026D01*
X181255Y986491D01*
X181140Y986904D01*
X180987Y987214D01*
X180757Y987473D01*
X180450Y987576D01*
G01X183550D02*
X183243Y987473D01*
X183013Y987214D01*
X182860Y986904D01*
X182745Y986491D01*
X182707Y986026D01*
X182745Y985561D01*
X182860Y985148D01*
X183013Y984838D01*
X183243Y984579D01*
X183550Y984476D01*
X183857Y984579D01*
X184087Y984838D01*
X184240Y985148D01*
X184355Y985561D01*
X184393Y986026D01*
X184355Y986491D01*
X184240Y986904D01*
X184087Y987214D01*
X183857Y987473D01*
X183550Y987576D01*
G01X185922Y989358D02*
X179722D01*
Y992558D01*
X185922D01*
Y989358D01*
G01X186157Y977554D02*
X179957D01*
Y980754D01*
X186157D01*
Y977554D01*
G01X185878Y994958D02*
X179678D01*
Y998158D01*
X185878D01*
Y994958D01*
G01X219206Y1032544D02*
G03I-16800J0D01*
G01X186989Y1012316D02*
Y1015416D01*
X187948D01*
X188254Y1015261D01*
X188446Y1015054D01*
X188523Y1014641D01*
X188446Y1014228D01*
X188216Y1013969D01*
X187948Y1013814D01*
X186989D01*
G01X187948D02*
X188523Y1012316D01*
G01X190856D02*
Y1015416D01*
X190396Y1014796D01*
G01Y1012316D02*
X191316D01*
G01X193956Y1015416D02*
X193649Y1015313D01*
X193419Y1015054D01*
X193266Y1014744D01*
X193151Y1014331D01*
X193113Y1013866D01*
X193151Y1013401D01*
X193266Y1012988D01*
X193419Y1012678D01*
X193649Y1012419D01*
X193956Y1012316D01*
X194263Y1012419D01*
X194493Y1012678D01*
X194646Y1012988D01*
X194761Y1013401D01*
X194799Y1013866D01*
X194761Y1014331D01*
X194646Y1014744D01*
X194493Y1015054D01*
X194263Y1015313D01*
X193956Y1015416D01*
G01X196979Y1012316D02*
X197056Y1012988D01*
X197171Y1013556D01*
X197324Y1014073D01*
X197516Y1014641D01*
X197823Y1015416D01*
X196289D01*
G01X185643Y1013713D02*
X179443D01*
Y1016913D01*
X185643D01*
Y1013713D01*
G01X186991Y1007344D02*
Y1010444D01*
X187950D01*
X188256Y1010289D01*
X188448Y1010082D01*
X188525Y1009669D01*
X188448Y1009256D01*
X188218Y1008997D01*
X187950Y1008842D01*
X186991D01*
G01X187950D02*
X188525Y1007344D01*
G01X190858D02*
Y1010444D01*
X190398Y1009824D01*
G01Y1007344D02*
X191318D01*
G01X193958Y1010444D02*
X193651Y1010341D01*
X193421Y1010082D01*
X193268Y1009772D01*
X193153Y1009359D01*
X193115Y1008894D01*
X193153Y1008429D01*
X193268Y1008016D01*
X193421Y1007706D01*
X193651Y1007447D01*
X193958Y1007344D01*
X194265Y1007447D01*
X194495Y1007706D01*
X194648Y1008016D01*
X194763Y1008429D01*
X194801Y1008894D01*
X194763Y1009359D01*
X194648Y1009772D01*
X194495Y1010082D01*
X194265Y1010341D01*
X193958Y1010444D01*
G01X197058Y1007344D02*
X197326Y1007396D01*
X197633Y1007551D01*
X197825Y1007809D01*
X197901Y1008171D01*
X197825Y1008532D01*
X197595Y1008842D01*
X197250Y1008997D01*
X196866D01*
X196636Y1009101D01*
X196445Y1009359D01*
X196368Y1009721D01*
X196483Y1010082D01*
X196751Y1010341D01*
X197058Y1010444D01*
X197365Y1010341D01*
X197633Y1010082D01*
X197748Y1009721D01*
X197671Y1009359D01*
X197480Y1009101D01*
X197250Y1008997D01*
X196866D01*
X196521Y1008842D01*
X196291Y1008532D01*
X196215Y1008171D01*
X196291Y1007809D01*
X196483Y1007551D01*
X196790Y1007396D01*
X197058Y1007344D01*
G01X185640Y1008113D02*
X179440D01*
Y1011313D01*
X185640D01*
Y1008113D01*
G01X174404Y999738D02*
Y1002838D01*
X175363D01*
X175669Y1002683D01*
X175861Y1002476D01*
X175938Y1002063D01*
X175861Y1001650D01*
X175631Y1001391D01*
X175363Y1001236D01*
X174404D01*
G01X175363D02*
X175938Y999738D01*
G01X177619Y1000100D02*
X177888Y999841D01*
X178194Y999738D01*
X178501Y999841D01*
X178769Y1000151D01*
X178961Y1000616D01*
X179038Y1001081D01*
Y1001650D01*
X178961Y1002115D01*
X178769Y1002528D01*
X178539Y1002735D01*
X178271Y1002838D01*
X177964Y1002735D01*
X177734Y1002528D01*
X177581Y1002218D01*
X177504Y1001805D01*
X177581Y1001443D01*
X177773Y1001081D01*
X178003Y1000875D01*
X178271Y1000823D01*
X178578Y1000926D01*
X178808Y1001185D01*
X179038Y1001650D01*
G01X180719Y1000100D02*
X180988Y999841D01*
X181294Y999738D01*
X181601Y999841D01*
X181869Y1000151D01*
X182061Y1000616D01*
X182138Y1001081D01*
Y1001650D01*
X182061Y1002115D01*
X181869Y1002528D01*
X181639Y1002735D01*
X181371Y1002838D01*
X181064Y1002735D01*
X180834Y1002528D01*
X180681Y1002218D01*
X180604Y1001805D01*
X180681Y1001443D01*
X180873Y1001081D01*
X181103Y1000875D01*
X181371Y1000823D01*
X181678Y1000926D01*
X181908Y1001185D01*
X182138Y1001650D01*
G01X183854Y1023422D02*
X177654D01*
Y1026622D01*
X183854D01*
Y1023422D01*
G01X183852Y1029022D02*
X177652D01*
Y1032222D01*
X183852D01*
Y1029022D01*
G01X214940Y1122856D02*
G03I-16800J0D01*
G01X173510Y1111215D02*
X170410D01*
Y1112174D01*
X170565Y1112480D01*
X170772Y1112672D01*
X171185Y1112749D01*
X171598Y1112672D01*
X171857Y1112442D01*
X172012Y1112174D01*
Y1111215D01*
G01Y1112174D02*
X173510Y1112749D01*
G01X170927Y1114354D02*
X170617Y1114584D01*
X170462Y1114852D01*
X170410Y1115159D01*
X170513Y1115542D01*
X170772Y1115810D01*
X171082Y1115887D01*
X171392Y1115849D01*
X171650Y1115695D01*
X172167Y1114929D01*
X172528Y1114584D01*
X173045Y1114354D01*
X173510Y1114277D01*
Y1115887D01*
G01Y1118182D02*
X170410D01*
X171030Y1117722D01*
G01X173510D02*
Y1118642D01*
G01X177390Y1105435D02*
Y1108535D01*
X178310D01*
X178617Y1108380D01*
X178847Y1108018D01*
X178924Y1107605D01*
X178847Y1107192D01*
X178655Y1106882D01*
X178310Y1106727D01*
X177390D01*
G01X181257Y1105435D02*
Y1108535D01*
X180797Y1107915D01*
G01Y1105435D02*
X181717D01*
G01X215032Y1206233D02*
G03I-16800J0D01*
G01X215536Y1299104D02*
G03I-16800J0D01*
G01X170944Y1280820D02*
Y1283920D01*
X171864D01*
X172171Y1283765D01*
X172401Y1283403D01*
X172478Y1282990D01*
X172401Y1282577D01*
X172209Y1282267D01*
X171864Y1282112D01*
X170944D01*
G01X174811Y1280820D02*
Y1283920D01*
X174351Y1283300D01*
G01Y1280820D02*
X175271D01*
G01X194186Y1323741D02*
X193956Y1323896D01*
X193688Y1323999D01*
X193381D01*
X193036Y1323844D01*
X192768Y1323586D01*
X192576Y1323276D01*
X192423Y1322759D01*
X192385Y1322294D01*
X192461Y1321829D01*
X192576Y1321519D01*
X192806Y1321209D01*
X193075Y1321002D01*
X193343Y1320899D01*
X193611D01*
X193880Y1321002D01*
X194110Y1321157D01*
X194301Y1321364D01*
G01X197210Y1320899D02*
X195676D01*
Y1323999D01*
X197210D01*
G01X196596Y1322501D02*
X195676D01*
G01X199543Y1320899D02*
Y1323999D01*
X199083Y1323379D01*
G01Y1320899D02*
X200003D01*
G01X201800Y1321364D02*
X202030Y1321106D01*
X202298Y1320951D01*
X202643Y1320899D01*
X202988Y1321002D01*
X203256Y1321209D01*
X203448Y1321571D01*
X203486Y1321984D01*
X203410Y1322397D01*
X203218Y1322656D01*
X202950Y1322862D01*
X202681Y1322914D01*
X202413Y1322862D01*
X202068Y1322656D01*
X202183Y1323999D01*
X203218D01*
G01X214242Y1380966D02*
G03I-16800J0D01*
G01X178050Y1455218D02*
Y1458318D01*
X178970D01*
X179277Y1458163D01*
X179507Y1457801D01*
X179584Y1457388D01*
X179507Y1456975D01*
X179315Y1456665D01*
X178970Y1456510D01*
X178050D01*
G01X181917Y1455218D02*
Y1458318D01*
X181457Y1457698D01*
G01Y1455218D02*
X182377D01*
G01X213153Y1474162D02*
G03I-16800J0D01*
G01X214769Y1557277D02*
G03I-16800J0D01*
G01X215833Y1648177D02*
G03I-16800J0D01*
G01X172917Y1630669D02*
Y1633769D01*
X173837D01*
X174144Y1633614D01*
X174374Y1633252D01*
X174451Y1632839D01*
X174374Y1632426D01*
X174182Y1632116D01*
X173837Y1631961D01*
X172917D01*
G01X176784Y1630669D02*
Y1633769D01*
X176324Y1633149D01*
G01Y1630669D02*
X177244D01*
G01X175599Y1663960D02*
X175369Y1664115D01*
X175101Y1664218D01*
X174794D01*
X174449Y1664063D01*
X174181Y1663805D01*
X173989Y1663495D01*
X173836Y1662978D01*
X173798Y1662513D01*
X173874Y1662048D01*
X173989Y1661738D01*
X174219Y1661428D01*
X174488Y1661221D01*
X174756Y1661118D01*
X175024D01*
X175293Y1661221D01*
X175523Y1661376D01*
X175714Y1661583D01*
G01X178623Y1661118D02*
X177089D01*
Y1664218D01*
X178623D01*
G01X178009Y1662720D02*
X177089D01*
G01X180956Y1661118D02*
Y1664218D01*
X180496Y1663598D01*
G01Y1661118D02*
X181416D01*
G01X183404Y1661480D02*
X183673Y1661221D01*
X183979Y1661118D01*
X184286Y1661221D01*
X184554Y1661531D01*
X184746Y1661996D01*
X184823Y1662461D01*
Y1663030D01*
X184746Y1663495D01*
X184554Y1663908D01*
X184324Y1664115D01*
X184056Y1664218D01*
X183749Y1664115D01*
X183519Y1663908D01*
X183366Y1663598D01*
X183289Y1663185D01*
X183366Y1662823D01*
X183558Y1662461D01*
X183788Y1662255D01*
X184056Y1662203D01*
X184363Y1662306D01*
X184593Y1662565D01*
X184823Y1663030D01*
G01X215297Y1731351D02*
G03I-16800J0D01*
G01X171338Y1787109D02*
Y1790209D01*
X172258D01*
X172565Y1790054D01*
X172795Y1789692D01*
X172872Y1789279D01*
X172795Y1788866D01*
X172603Y1788556D01*
X172258Y1788401D01*
X171338D01*
G01X175205Y1787109D02*
Y1790209D01*
X174745Y1789589D01*
G01Y1787109D02*
X175665D01*
G01X215220Y1823227D02*
G03I-16800J0D01*
G01X213979Y1900420D02*
G03I-16800J0D01*
G01X186931Y1919337D02*
Y1922437D01*
X187851D01*
X188158Y1922282D01*
X188388Y1921920D01*
X188465Y1921507D01*
X188388Y1921094D01*
X188196Y1920784D01*
X187851Y1920629D01*
X186931D01*
G01X190031Y1919337D02*
Y1922437D01*
X190990D01*
X191296Y1922282D01*
X191488Y1922075D01*
X191565Y1921662D01*
X191488Y1921249D01*
X191258Y1920990D01*
X190990Y1920835D01*
X190031D01*
G01X190990D02*
X191565Y1919337D01*
G01X194665D02*
X193131D01*
Y1922437D01*
X194665D01*
G01X194051Y1920939D02*
X193131D01*
G01X196193Y1919750D02*
X196500Y1919492D01*
X196845Y1919337D01*
X197151D01*
X197458Y1919492D01*
X197688Y1919750D01*
X197803Y1920112D01*
X197726Y1920474D01*
X197535Y1920784D01*
X197190Y1920990D01*
X196730Y1921094D01*
X196461Y1921300D01*
X196346Y1921662D01*
X196423Y1922024D01*
X196615Y1922282D01*
X196883Y1922437D01*
X197151D01*
X197420Y1922334D01*
X197650Y1922075D01*
G01X199293Y1919750D02*
X199600Y1919492D01*
X199945Y1919337D01*
X200251D01*
X200558Y1919492D01*
X200788Y1919750D01*
X200903Y1920112D01*
X200826Y1920474D01*
X200635Y1920784D01*
X200290Y1920990D01*
X199830Y1921094D01*
X199561Y1921300D01*
X199446Y1921662D01*
X199523Y1922024D01*
X199715Y1922282D01*
X199983Y1922437D01*
X200251D01*
X200520Y1922334D01*
X200750Y1922075D01*
G01X202700Y1920370D02*
X203696D01*
G01X205570Y1919337D02*
Y1922437D01*
X207026D01*
G01X206490Y1920939D02*
X205570D01*
G01X208938Y1922437D02*
X209858D01*
G01X209398D02*
Y1919337D01*
G01X208938D02*
X209858D01*
G01X212498Y1922437D02*
Y1919337D01*
G01X211616Y1922437D02*
X213380D01*
G01X215815Y1998730D02*
G03I-16800J0D01*
G01X170811Y1980123D02*
Y1983223D01*
X171731D01*
X172038Y1983068D01*
X172268Y1982706D01*
X172345Y1982293D01*
X172268Y1981880D01*
X172076Y1981570D01*
X171731Y1981415D01*
X170811D01*
G01X174678Y1980123D02*
Y1983223D01*
X174218Y1982603D01*
G01Y1980123D02*
X175138D01*
G01X190223Y2021792D02*
X189993Y2021947D01*
X189725Y2022050D01*
X189418D01*
X189073Y2021895D01*
X188805Y2021637D01*
X188613Y2021327D01*
X188460Y2020810D01*
X188422Y2020345D01*
X188498Y2019880D01*
X188613Y2019570D01*
X188843Y2019260D01*
X189112Y2019053D01*
X189380Y2018950D01*
X189648D01*
X189917Y2019053D01*
X190147Y2019208D01*
X190338Y2019415D01*
G01X193247Y2018950D02*
X191713D01*
Y2022050D01*
X193247D01*
G01X192633Y2020552D02*
X191713D01*
G01X194852Y2021533D02*
X195082Y2021843D01*
X195350Y2021998D01*
X195657Y2022050D01*
X196040Y2021947D01*
X196308Y2021688D01*
X196385Y2021378D01*
X196347Y2021068D01*
X196193Y2020810D01*
X195427Y2020293D01*
X195082Y2019932D01*
X194852Y2019415D01*
X194775Y2018950D01*
X196385D01*
G01X197837Y2019570D02*
X198067Y2019208D01*
X198373Y2019002D01*
X198718Y2018950D01*
X199025Y2019002D01*
X199332Y2019260D01*
X199523Y2019570D01*
X199562Y2019880D01*
X199485Y2020242D01*
X199217Y2020500D01*
X198948Y2020603D01*
X198603D01*
G01X198948D02*
X199178Y2020758D01*
X199370Y2021017D01*
X199447Y2021327D01*
X199370Y2021637D01*
X199178Y2021895D01*
X198833Y2022050D01*
X198488Y2021998D01*
X198143Y2021792D01*
G01X215220Y2043388D02*
G03I-16800J0D01*
G01X213400Y-103934D02*
X214200Y-104600D01*
X215100Y-105000D01*
X215900D01*
X216700Y-104600D01*
X217300Y-103934D01*
X217600Y-103000D01*
X217400Y-102067D01*
X216900Y-101267D01*
X216000Y-100733D01*
X214800Y-100467D01*
X214100Y-99933D01*
X213800Y-99000D01*
X214000Y-98067D01*
X214500Y-97400D01*
X215200Y-97000D01*
X215900D01*
X216600Y-97267D01*
X217200Y-97933D01*
G01X222300Y-97000D02*
X224700D01*
G01X223500D02*
Y-105000D01*
G01X222300D02*
X224700D01*
G01X229500Y-97000D02*
Y-105000D01*
X233500D01*
G01X237300D02*
Y-97000D01*
G01X241100D02*
X237300Y-101934D01*
G01X241700Y-105000D02*
X239000Y-99667D01*
G01X246200Y-102333D02*
X248800D01*
G01X255500Y-97000D02*
Y-105000D01*
G01X253200Y-97000D02*
X257800D01*
G01X263500Y-105000D02*
X262700Y-104867D01*
X262000Y-104333D01*
X261400Y-103533D01*
X261000Y-102600D01*
X260800Y-101533D01*
Y-100467D01*
X261000Y-99400D01*
X261400Y-98467D01*
X262000Y-97667D01*
X262700Y-97133D01*
X263500Y-97000D01*
X264300Y-97133D01*
X265000Y-97667D01*
X265600Y-98467D01*
X266000Y-99400D01*
X266200Y-100467D01*
Y-101533D01*
X266000Y-102600D01*
X265600Y-103533D01*
X265000Y-104333D01*
X264300Y-104867D01*
X263500Y-105000D01*
G01X269500D02*
Y-97000D01*
X271900D01*
X272700Y-97400D01*
X273300Y-98333D01*
X273500Y-99400D01*
X273300Y-100467D01*
X272800Y-101267D01*
X271900Y-101667D01*
X269500D01*
G01X202000Y-72000D02*
Y-80000D01*
X206000D01*
G01X213800D02*
Y-74667D01*
G01Y-75600D02*
X213400Y-75067D01*
X212800Y-74800D01*
X212100Y-74667D01*
X211400Y-74933D01*
X210800Y-75467D01*
X210400Y-76267D01*
X210200Y-77333D01*
X210400Y-78400D01*
X210800Y-79200D01*
X211400Y-79733D01*
X212100Y-80000D01*
X212800Y-79867D01*
X213400Y-79467D01*
X213800Y-78934D01*
G01X217900Y-82400D02*
X218500Y-82667D01*
X219300Y-82400D01*
X219800Y-81867D01*
X220200Y-81200D01*
X220800Y-79067D01*
X222100Y-74667D01*
G01X218900D02*
X220800Y-79067D01*
G01X226500Y-76400D02*
X229700D01*
X229400Y-75467D01*
X228900Y-74933D01*
X228200Y-74667D01*
X227500Y-74800D01*
X226900Y-75200D01*
X226500Y-76133D01*
X226300Y-76934D01*
Y-77733D01*
X226500Y-78533D01*
X227000Y-79333D01*
X227600Y-79867D01*
X228300Y-80000D01*
X229000Y-79733D01*
X229700Y-78934D01*
G01X234600Y-80000D02*
Y-74667D01*
G01Y-75733D02*
X235100Y-75200D01*
X235600Y-74800D01*
X236300Y-74667D01*
X236800Y-74800D01*
X237400Y-75200D01*
G01X208051Y56284D02*
Y59384D01*
X208971D01*
X209278Y59229D01*
X209508Y58867D01*
X209585Y58454D01*
X209508Y58041D01*
X209316Y57731D01*
X208971Y57576D01*
X208051D01*
G01X211151Y56284D02*
Y59384D01*
X212110D01*
X212416Y59229D01*
X212608Y59022D01*
X212685Y58609D01*
X212608Y58196D01*
X212378Y57937D01*
X212110Y57782D01*
X211151D01*
G01X212110D02*
X212685Y56284D01*
G01X215785D02*
X214251D01*
Y59384D01*
X215785D01*
G01X215171Y57886D02*
X214251D01*
G01X217313Y56697D02*
X217620Y56439D01*
X217965Y56284D01*
X218271D01*
X218578Y56439D01*
X218808Y56697D01*
X218923Y57059D01*
X218846Y57421D01*
X218655Y57731D01*
X218310Y57937D01*
X217850Y58041D01*
X217581Y58247D01*
X217466Y58609D01*
X217543Y58971D01*
X217735Y59229D01*
X218003Y59384D01*
X218271D01*
X218540Y59281D01*
X218770Y59022D01*
G01X220413Y56697D02*
X220720Y56439D01*
X221065Y56284D01*
X221371D01*
X221678Y56439D01*
X221908Y56697D01*
X222023Y57059D01*
X221946Y57421D01*
X221755Y57731D01*
X221410Y57937D01*
X220950Y58041D01*
X220681Y58247D01*
X220566Y58609D01*
X220643Y58971D01*
X220835Y59229D01*
X221103Y59384D01*
X221371D01*
X221640Y59281D01*
X221870Y59022D01*
G01X223820Y57317D02*
X224816D01*
G01X226690Y56284D02*
Y59384D01*
X228146D01*
G01X227610Y57886D02*
X226690D01*
G01X230058Y59384D02*
X230978D01*
G01X230518D02*
Y56284D01*
G01X230058D02*
X230978D01*
G01X233618Y59384D02*
Y56284D01*
G01X232736Y59384D02*
X234500D01*
G01X215164Y62518D02*
X212924D01*
G01X214137Y60893D02*
Y64143D01*
G01X216551Y69400D02*
X216321Y69555D01*
X216053Y69658D01*
X215746D01*
X215401Y69503D01*
X215133Y69245D01*
X214941Y68935D01*
X214788Y68418D01*
X214750Y67953D01*
X214826Y67488D01*
X214941Y67178D01*
X215171Y66868D01*
X215440Y66661D01*
X215708Y66558D01*
X215976D01*
X216245Y66661D01*
X216475Y66816D01*
X216666Y67023D01*
G01X219575Y66558D02*
X218041D01*
Y69658D01*
X219575D01*
G01X218961Y68160D02*
X218041D01*
G01X221908Y66558D02*
Y69658D01*
X221448Y69038D01*
G01Y66558D02*
X222368D01*
G01X196652Y56305D02*
Y89905D01*
G01X197179Y135250D02*
Y168850D01*
G01X212664Y166687D02*
X210424D01*
G01X211637Y165062D02*
Y168312D01*
G01X218113Y246018D02*
X215873D01*
G01X217086Y244393D02*
Y247643D01*
G01X197247Y230768D02*
Y264368D01*
G01X215089Y258696D02*
X214859Y258851D01*
X214591Y258954D01*
X214284D01*
X213939Y258799D01*
X213671Y258541D01*
X213479Y258231D01*
X213326Y257714D01*
X213288Y257249D01*
X213364Y256784D01*
X213479Y256474D01*
X213709Y256164D01*
X213978Y255957D01*
X214246Y255854D01*
X214514D01*
X214783Y255957D01*
X215013Y256112D01*
X215204Y256319D01*
G01X218113Y255854D02*
X216579D01*
Y258954D01*
X218113D01*
G01X217499Y257456D02*
X216579D01*
G01X219603Y256474D02*
X219833Y256112D01*
X220139Y255906D01*
X220484Y255854D01*
X220791Y255906D01*
X221098Y256164D01*
X221289Y256474D01*
X221328Y256784D01*
X221251Y257146D01*
X220983Y257404D01*
X220714Y257507D01*
X220369D01*
G01X220714D02*
X220944Y257662D01*
X221136Y257921D01*
X221213Y258231D01*
X221136Y258541D01*
X220944Y258799D01*
X220599Y258954D01*
X220254Y258902D01*
X219909Y258696D01*
G01X210125Y316402D02*
X207885D01*
G01X209098Y314777D02*
Y318027D01*
G01X197707Y314986D02*
Y348586D01*
G01X217067Y342906D02*
Y346006D01*
X217987D01*
X218294Y345851D01*
X218524Y345489D01*
X218601Y345076D01*
X218524Y344663D01*
X218332Y344353D01*
X217987Y344198D01*
X217067D01*
G01X220167Y342906D02*
Y346006D01*
X221126D01*
X221432Y345851D01*
X221624Y345644D01*
X221701Y345231D01*
X221624Y344818D01*
X221394Y344559D01*
X221126Y344404D01*
X220167D01*
G01X221126D02*
X221701Y342906D01*
G01X224801D02*
X223267D01*
Y346006D01*
X224801D01*
G01X224187Y344508D02*
X223267D01*
G01X226329Y343319D02*
X226636Y343061D01*
X226981Y342906D01*
X227287D01*
X227594Y343061D01*
X227824Y343319D01*
X227939Y343681D01*
X227862Y344043D01*
X227671Y344353D01*
X227326Y344559D01*
X226866Y344663D01*
X226597Y344869D01*
X226482Y345231D01*
X226559Y345593D01*
X226751Y345851D01*
X227019Y346006D01*
X227287D01*
X227556Y345903D01*
X227786Y345644D01*
G01X229429Y343319D02*
X229736Y343061D01*
X230081Y342906D01*
X230387D01*
X230694Y343061D01*
X230924Y343319D01*
X231039Y343681D01*
X230962Y344043D01*
X230771Y344353D01*
X230426Y344559D01*
X229966Y344663D01*
X229697Y344869D01*
X229582Y345231D01*
X229659Y345593D01*
X229851Y345851D01*
X230119Y346006D01*
X230387D01*
X230656Y345903D01*
X230886Y345644D01*
G01X232836Y343939D02*
X233832D01*
G01X235706Y342906D02*
Y346006D01*
X237162D01*
G01X236626Y344508D02*
X235706D01*
G01X239074Y346006D02*
X239994D01*
G01X239534D02*
Y342906D01*
G01X239074D02*
X239994D01*
G01X242634Y346006D02*
Y342906D01*
G01X241752Y346006D02*
X243516D01*
G01X219718Y415917D02*
X217478D01*
G01X218691Y414292D02*
Y417542D01*
G01X196651Y404932D02*
Y438532D01*
G01X219176Y425834D02*
X218946Y425989D01*
X218678Y426092D01*
X218371D01*
X218026Y425937D01*
X217758Y425679D01*
X217566Y425369D01*
X217413Y424852D01*
X217375Y424387D01*
X217451Y423922D01*
X217566Y423612D01*
X217796Y423302D01*
X218065Y423095D01*
X218333Y422992D01*
X218601D01*
X218870Y423095D01*
X219100Y423250D01*
X219291Y423457D01*
G01X222200Y422992D02*
X220666D01*
Y426092D01*
X222200D01*
G01X221586Y424594D02*
X220666D01*
G01X223690Y423457D02*
X223920Y423199D01*
X224188Y423044D01*
X224533Y422992D01*
X224878Y423095D01*
X225146Y423302D01*
X225338Y423664D01*
X225376Y424077D01*
X225300Y424490D01*
X225108Y424749D01*
X224840Y424955D01*
X224571Y425007D01*
X224303Y424955D01*
X223958Y424749D01*
X224073Y426092D01*
X225108D01*
G01X196310Y486226D02*
X196080Y486381D01*
X195812Y486484D01*
X195505D01*
X195160Y486329D01*
X194892Y486071D01*
X194700Y485761D01*
X194547Y485244D01*
X194509Y484779D01*
X194585Y484314D01*
X194700Y484004D01*
X194930Y483694D01*
X195199Y483487D01*
X195467Y483384D01*
X195735D01*
X196004Y483487D01*
X196234Y483642D01*
X196425Y483849D01*
G01X199334Y483384D02*
X197800D01*
Y486484D01*
X199334D01*
G01X198720Y484986D02*
X197800D01*
G01X200939Y484676D02*
X201207Y485037D01*
X201437Y485244D01*
X201744Y485347D01*
X202012Y485244D01*
X202204Y485037D01*
X202357Y484727D01*
X202395Y484366D01*
X202357Y484056D01*
X202204Y483746D01*
X201974Y483487D01*
X201705Y483384D01*
X201399Y483487D01*
X201130Y483797D01*
X200977Y484262D01*
X200939Y484779D01*
X201015Y485451D01*
X201130Y485812D01*
X201322Y486174D01*
X201590Y486432D01*
X201859Y486484D01*
X202127Y486381D01*
X202319Y486122D01*
G01X197443Y489717D02*
Y523317D01*
G01X217945Y499480D02*
X215705D01*
G01X216918Y497855D02*
Y501105D01*
G01X208357Y520860D02*
Y523960D01*
X209277D01*
X209584Y523805D01*
X209814Y523443D01*
X209891Y523030D01*
X209814Y522617D01*
X209622Y522307D01*
X209277Y522152D01*
X208357D01*
G01X211457Y520860D02*
Y523960D01*
X212416D01*
X212722Y523805D01*
X212914Y523598D01*
X212991Y523185D01*
X212914Y522772D01*
X212684Y522513D01*
X212416Y522358D01*
X211457D01*
G01X212416D02*
X212991Y520860D01*
G01X216091D02*
X214557D01*
Y523960D01*
X216091D01*
G01X215477Y522462D02*
X214557D01*
G01X217619Y521273D02*
X217926Y521015D01*
X218271Y520860D01*
X218577D01*
X218884Y521015D01*
X219114Y521273D01*
X219229Y521635D01*
X219152Y521997D01*
X218961Y522307D01*
X218616Y522513D01*
X218156Y522617D01*
X217887Y522823D01*
X217772Y523185D01*
X217849Y523547D01*
X218041Y523805D01*
X218309Y523960D01*
X218577D01*
X218846Y523857D01*
X219076Y523598D01*
G01X220719Y521273D02*
X221026Y521015D01*
X221371Y520860D01*
X221677D01*
X221984Y521015D01*
X222214Y521273D01*
X222329Y521635D01*
X222252Y521997D01*
X222061Y522307D01*
X221716Y522513D01*
X221256Y522617D01*
X220987Y522823D01*
X220872Y523185D01*
X220949Y523547D01*
X221141Y523805D01*
X221409Y523960D01*
X221677D01*
X221946Y523857D01*
X222176Y523598D01*
G01X224126Y521893D02*
X225122D01*
G01X226996Y520860D02*
Y523960D01*
X228452D01*
G01X227916Y522462D02*
X226996D01*
G01X230364Y523960D02*
X231284D01*
G01X230824D02*
Y520860D01*
G01X230364D02*
X231284D01*
G01X233924Y523960D02*
Y520860D01*
G01X233042Y523960D02*
X234806D01*
G01X217677Y585807D02*
X215437D01*
G01X216650Y584182D02*
Y587432D01*
G01X199778Y581330D02*
Y614930D01*
G01X218549Y593477D02*
X218319Y593632D01*
X218051Y593735D01*
X217744D01*
X217399Y593580D01*
X217131Y593322D01*
X216939Y593012D01*
X216786Y592495D01*
X216748Y592030D01*
X216824Y591565D01*
X216939Y591255D01*
X217169Y590945D01*
X217438Y590738D01*
X217706Y590635D01*
X217974D01*
X218243Y590738D01*
X218473Y590893D01*
X218664Y591100D01*
G01X221573Y590635D02*
X220039D01*
Y593735D01*
X221573D01*
G01X220959Y592237D02*
X220039D01*
G01X223906Y590635D02*
X224174Y590687D01*
X224481Y590842D01*
X224673Y591100D01*
X224749Y591462D01*
X224673Y591823D01*
X224443Y592133D01*
X224098Y592288D01*
X223714D01*
X223484Y592392D01*
X223293Y592650D01*
X223216Y593012D01*
X223331Y593373D01*
X223599Y593632D01*
X223906Y593735D01*
X224213Y593632D01*
X224481Y593373D01*
X224596Y593012D01*
X224519Y592650D01*
X224328Y592392D01*
X224098Y592288D01*
X223714D01*
X223369Y592133D01*
X223139Y591823D01*
X223063Y591462D01*
X223139Y591100D01*
X223331Y590842D01*
X223638Y590687D01*
X223906Y590635D01*
G01X199429Y660336D02*
X199199Y660491D01*
X198931Y660594D01*
X198624D01*
X198279Y660439D01*
X198011Y660181D01*
X197819Y659871D01*
X197666Y659354D01*
X197628Y658889D01*
X197704Y658424D01*
X197819Y658114D01*
X198049Y657804D01*
X198318Y657597D01*
X198586Y657494D01*
X198854D01*
X199123Y657597D01*
X199353Y657752D01*
X199544Y657959D01*
G01X202453Y657494D02*
X200919D01*
Y660594D01*
X202453D01*
G01X201839Y659096D02*
X200919D01*
G01X204134Y657856D02*
X204403Y657597D01*
X204709Y657494D01*
X205016Y657597D01*
X205284Y657907D01*
X205476Y658372D01*
X205553Y658837D01*
Y659406D01*
X205476Y659871D01*
X205284Y660284D01*
X205054Y660491D01*
X204786Y660594D01*
X204479Y660491D01*
X204249Y660284D01*
X204096Y659974D01*
X204019Y659561D01*
X204096Y659199D01*
X204288Y658837D01*
X204518Y658631D01*
X204786Y658579D01*
X205093Y658682D01*
X205323Y658941D01*
X205553Y659406D01*
G01X221456Y685759D02*
X219216D01*
G01X220429Y684134D02*
Y687384D01*
G01X197706Y664845D02*
Y698445D01*
G01X219981Y768637D02*
X217741D01*
G01X218954Y767012D02*
Y770262D01*
G01X198736Y757726D02*
Y791326D01*
G01X220460Y852152D02*
X218220D01*
G01X219433Y850527D02*
Y853777D01*
G01X198496Y839444D02*
Y873044D01*
G01X219908Y859782D02*
X219678Y859937D01*
X219410Y860040D01*
X219103D01*
X218758Y859885D01*
X218490Y859627D01*
X218298Y859317D01*
X218145Y858800D01*
X218107Y858335D01*
X218183Y857870D01*
X218298Y857560D01*
X218528Y857250D01*
X218797Y857043D01*
X219065Y856940D01*
X219333D01*
X219602Y857043D01*
X219832Y857198D01*
X220023Y857405D01*
G01X222932Y856940D02*
X221398D01*
Y860040D01*
X222932D01*
G01X222318Y858542D02*
X221398D01*
G01X225265Y856940D02*
Y860040D01*
X224805Y859420D01*
G01Y856940D02*
X225725D01*
G01X228365D02*
Y860040D01*
X227905Y859420D01*
G01Y856940D02*
X228825D01*
G01X203201Y930402D02*
Y964002D01*
G01X202406Y1015744D02*
Y1049344D01*
G01X217305Y1049211D02*
X217075Y1049366D01*
X216807Y1049469D01*
X216500D01*
X216155Y1049314D01*
X215887Y1049056D01*
X215695Y1048746D01*
X215542Y1048229D01*
X215504Y1047764D01*
X215580Y1047299D01*
X215695Y1046989D01*
X215925Y1046679D01*
X216194Y1046472D01*
X216462Y1046369D01*
X216730D01*
X216999Y1046472D01*
X217229Y1046627D01*
X217420Y1046834D01*
G01X220329Y1046369D02*
X218795D01*
Y1049469D01*
X220329D01*
G01X219715Y1047971D02*
X218795D01*
G01X222585Y1046369D02*
X222662Y1047041D01*
X222777Y1047609D01*
X222930Y1048126D01*
X223122Y1048694D01*
X223429Y1049469D01*
X221895D01*
G01X218667Y1122356D02*
X216427D01*
G01X217640Y1120731D02*
Y1123981D01*
G01X198140Y1106056D02*
Y1139656D01*
G01X218510Y1131676D02*
X218280Y1131831D01*
X218012Y1131934D01*
X217705D01*
X217360Y1131779D01*
X217092Y1131521D01*
X216900Y1131211D01*
X216747Y1130694D01*
X216709Y1130229D01*
X216785Y1129764D01*
X216900Y1129454D01*
X217130Y1129144D01*
X217399Y1128937D01*
X217667Y1128834D01*
X217935D01*
X218204Y1128937D01*
X218434Y1129092D01*
X218625Y1129299D01*
G01X221534Y1128834D02*
X220000D01*
Y1131934D01*
X221534D01*
G01X220920Y1130436D02*
X220000D01*
G01X223867Y1128834D02*
Y1131934D01*
X223407Y1131314D01*
G01Y1128834D02*
X224327D01*
G01X226124Y1129454D02*
X226354Y1129092D01*
X226660Y1128886D01*
X227005Y1128834D01*
X227312Y1128886D01*
X227619Y1129144D01*
X227810Y1129454D01*
X227849Y1129764D01*
X227772Y1130126D01*
X227504Y1130384D01*
X227235Y1130487D01*
X226890D01*
G01X227235D02*
X227465Y1130642D01*
X227657Y1130901D01*
X227734Y1131211D01*
X227657Y1131521D01*
X227465Y1131779D01*
X227120Y1131934D01*
X226775Y1131882D01*
X226430Y1131676D01*
G01X198232Y1189433D02*
Y1223033D01*
G01X218759Y1205733D02*
X216519D01*
G01X217732Y1204108D02*
Y1207358D01*
G01X212589Y1220560D02*
Y1223660D01*
X213509D01*
X213816Y1223505D01*
X214046Y1223143D01*
X214123Y1222730D01*
X214046Y1222317D01*
X213854Y1222007D01*
X213509Y1221852D01*
X212589D01*
G01X215689Y1220560D02*
Y1223660D01*
X216648D01*
X216954Y1223505D01*
X217146Y1223298D01*
X217223Y1222885D01*
X217146Y1222472D01*
X216916Y1222213D01*
X216648Y1222058D01*
X215689D01*
G01X216648D02*
X217223Y1220560D01*
G01X220323D02*
X218789D01*
Y1223660D01*
X220323D01*
G01X219709Y1222162D02*
X218789D01*
G01X221851Y1220973D02*
X222158Y1220715D01*
X222503Y1220560D01*
X222809D01*
X223116Y1220715D01*
X223346Y1220973D01*
X223461Y1221335D01*
X223384Y1221697D01*
X223193Y1222007D01*
X222848Y1222213D01*
X222388Y1222317D01*
X222119Y1222523D01*
X222004Y1222885D01*
X222081Y1223247D01*
X222273Y1223505D01*
X222541Y1223660D01*
X222809D01*
X223078Y1223557D01*
X223308Y1223298D01*
G01X224951Y1220973D02*
X225258Y1220715D01*
X225603Y1220560D01*
X225909D01*
X226216Y1220715D01*
X226446Y1220973D01*
X226561Y1221335D01*
X226484Y1221697D01*
X226293Y1222007D01*
X225948Y1222213D01*
X225488Y1222317D01*
X225219Y1222523D01*
X225104Y1222885D01*
X225181Y1223247D01*
X225373Y1223505D01*
X225641Y1223660D01*
X225909D01*
X226178Y1223557D01*
X226408Y1223298D01*
G01X228358Y1221593D02*
X229354D01*
G01X231228Y1220560D02*
Y1223660D01*
X232684D01*
G01X232148Y1222162D02*
X231228D01*
G01X234596Y1223660D02*
X235516D01*
G01X235056D02*
Y1220560D01*
G01X234596D02*
X235516D01*
G01X238156Y1223660D02*
Y1220560D01*
G01X237274Y1223660D02*
X239038D01*
G01X198736Y1282304D02*
Y1315904D01*
G01X219033Y1298205D02*
X216793D01*
G01X218006Y1296580D02*
Y1299830D01*
G01X218343Y1379508D02*
X216103D01*
G01X217316Y1377883D02*
Y1381133D01*
G01X197442Y1364166D02*
Y1397766D01*
G01X217974Y1390224D02*
X217744Y1390379D01*
X217476Y1390482D01*
X217169D01*
X216824Y1390327D01*
X216556Y1390069D01*
X216364Y1389759D01*
X216211Y1389242D01*
X216173Y1388777D01*
X216249Y1388312D01*
X216364Y1388002D01*
X216594Y1387692D01*
X216863Y1387485D01*
X217131Y1387382D01*
X217399D01*
X217668Y1387485D01*
X217898Y1387640D01*
X218089Y1387847D01*
G01X220998Y1387382D02*
X219464D01*
Y1390482D01*
X220998D01*
G01X220384Y1388984D02*
X219464D01*
G01X223331Y1387382D02*
Y1390482D01*
X222871Y1389862D01*
G01Y1387382D02*
X223791D01*
G01X225703Y1388674D02*
X225971Y1389035D01*
X226201Y1389242D01*
X226508Y1389345D01*
X226776Y1389242D01*
X226968Y1389035D01*
X227121Y1388725D01*
X227159Y1388364D01*
X227121Y1388054D01*
X226968Y1387744D01*
X226738Y1387485D01*
X226469Y1387382D01*
X226163Y1387485D01*
X225894Y1387795D01*
X225741Y1388260D01*
X225703Y1388777D01*
X225779Y1389449D01*
X225894Y1389810D01*
X226086Y1390172D01*
X226354Y1390430D01*
X226623Y1390482D01*
X226891Y1390379D01*
X227083Y1390120D01*
G01X216111Y1479035D02*
X213871D01*
G01X215084Y1477410D02*
Y1480660D01*
G01X219167Y1471353D02*
X218937Y1471508D01*
X218669Y1471611D01*
X218362D01*
X218017Y1471456D01*
X217749Y1471198D01*
X217557Y1470888D01*
X217404Y1470371D01*
X217366Y1469906D01*
X217442Y1469441D01*
X217557Y1469131D01*
X217787Y1468821D01*
X218056Y1468614D01*
X218324Y1468511D01*
X218592D01*
X218861Y1468614D01*
X219091Y1468769D01*
X219282Y1468976D01*
G01X222191Y1468511D02*
X220657D01*
Y1471611D01*
X222191D01*
G01X221577Y1470113D02*
X220657D01*
G01X224524Y1468511D02*
Y1471611D01*
X224064Y1470991D01*
G01Y1468511D02*
X224984D01*
G01X227547D02*
X227624Y1469183D01*
X227739Y1469751D01*
X227892Y1470268D01*
X228084Y1470836D01*
X228391Y1471611D01*
X226857D01*
G01X196353Y1457362D02*
Y1490962D01*
G01X219167Y1553611D02*
X216927D01*
G01X218140Y1551986D02*
Y1555236D01*
G01X215057Y1548008D02*
X214827Y1548163D01*
X214559Y1548266D01*
X214252D01*
X213907Y1548111D01*
X213639Y1547853D01*
X213447Y1547543D01*
X213294Y1547026D01*
X213256Y1546561D01*
X213332Y1546096D01*
X213447Y1545786D01*
X213677Y1545476D01*
X213946Y1545269D01*
X214214Y1545166D01*
X214482D01*
X214751Y1545269D01*
X214981Y1545424D01*
X215172Y1545631D01*
G01X218081Y1545166D02*
X216547D01*
Y1548266D01*
X218081D01*
G01X217467Y1546768D02*
X216547D01*
G01X220414Y1545166D02*
Y1548266D01*
X219954Y1547646D01*
G01Y1545166D02*
X220874D01*
G01X223514D02*
X223782Y1545218D01*
X224089Y1545373D01*
X224281Y1545631D01*
X224357Y1545993D01*
X224281Y1546354D01*
X224051Y1546664D01*
X223706Y1546819D01*
X223322D01*
X223092Y1546923D01*
X222901Y1547181D01*
X222824Y1547543D01*
X222939Y1547904D01*
X223207Y1548163D01*
X223514Y1548266D01*
X223821Y1548163D01*
X224089Y1547904D01*
X224204Y1547543D01*
X224127Y1547181D01*
X223936Y1546923D01*
X223706Y1546819D01*
X223322D01*
X222977Y1546664D01*
X222747Y1546354D01*
X222671Y1545993D01*
X222747Y1545631D01*
X222939Y1545373D01*
X223246Y1545218D01*
X223514Y1545166D01*
G01X197969Y1540477D02*
Y1574077D01*
G01X219862Y1653836D02*
X217622D01*
G01X218835Y1652211D02*
Y1655461D01*
G01X199033Y1631377D02*
Y1664977D01*
G01X198497Y1714551D02*
Y1748151D01*
G01X219024Y1730851D02*
X216784D01*
G01X217997Y1729226D02*
Y1732476D01*
G01X219550Y1743754D02*
X219320Y1743909D01*
X219052Y1744012D01*
X218745D01*
X218400Y1743857D01*
X218132Y1743599D01*
X217940Y1743289D01*
X217787Y1742772D01*
X217749Y1742307D01*
X217825Y1741842D01*
X217940Y1741532D01*
X218170Y1741222D01*
X218439Y1741015D01*
X218707Y1740912D01*
X218975D01*
X219244Y1741015D01*
X219474Y1741170D01*
X219665Y1741377D01*
G01X222574Y1740912D02*
X221040D01*
Y1744012D01*
X222574D01*
G01X221960Y1742514D02*
X221040D01*
G01X224179Y1743495D02*
X224409Y1743805D01*
X224677Y1743960D01*
X224984Y1744012D01*
X225367Y1743909D01*
X225635Y1743650D01*
X225712Y1743340D01*
X225674Y1743030D01*
X225520Y1742772D01*
X224754Y1742255D01*
X224409Y1741894D01*
X224179Y1741377D01*
X224102Y1740912D01*
X225712D01*
G01X228007Y1744012D02*
X227700Y1743909D01*
X227470Y1743650D01*
X227317Y1743340D01*
X227202Y1742927D01*
X227164Y1742462D01*
X227202Y1741997D01*
X227317Y1741584D01*
X227470Y1741274D01*
X227700Y1741015D01*
X228007Y1740912D01*
X228314Y1741015D01*
X228544Y1741274D01*
X228697Y1741584D01*
X228812Y1741997D01*
X228850Y1742462D01*
X228812Y1742927D01*
X228697Y1743340D01*
X228544Y1743650D01*
X228314Y1743909D01*
X228007Y1744012D01*
G01X218947Y1822727D02*
X216707D01*
G01X217920Y1821102D02*
Y1824352D01*
G01X198420Y1806427D02*
Y1840027D01*
G01X219805Y1833155D02*
X219575Y1833310D01*
X219307Y1833413D01*
X219000D01*
X218655Y1833258D01*
X218387Y1833000D01*
X218195Y1832690D01*
X218042Y1832173D01*
X218004Y1831708D01*
X218080Y1831243D01*
X218195Y1830933D01*
X218425Y1830623D01*
X218694Y1830416D01*
X218962Y1830313D01*
X219230D01*
X219499Y1830416D01*
X219729Y1830571D01*
X219920Y1830778D01*
G01X222829Y1830313D02*
X221295D01*
Y1833413D01*
X222829D01*
G01X222215Y1831915D02*
X221295D01*
G01X224434Y1832896D02*
X224664Y1833206D01*
X224932Y1833361D01*
X225239Y1833413D01*
X225622Y1833310D01*
X225890Y1833051D01*
X225967Y1832741D01*
X225929Y1832431D01*
X225775Y1832173D01*
X225009Y1831656D01*
X224664Y1831295D01*
X224434Y1830778D01*
X224357Y1830313D01*
X225967D01*
G01X227534Y1832896D02*
X227764Y1833206D01*
X228032Y1833361D01*
X228339Y1833413D01*
X228722Y1833310D01*
X228990Y1833051D01*
X229067Y1832741D01*
X229029Y1832431D01*
X228875Y1832173D01*
X228109Y1831656D01*
X227764Y1831295D01*
X227534Y1830778D01*
X227457Y1830313D01*
X229067D01*
G01X197179Y1883620D02*
Y1917220D01*
G01X218872Y1899600D02*
X216632D01*
G01X217845Y1897975D02*
Y1901225D01*
G01X216184Y1911346D02*
X215954Y1911501D01*
X215686Y1911604D01*
X215379D01*
X215034Y1911449D01*
X214766Y1911191D01*
X214574Y1910881D01*
X214421Y1910364D01*
X214383Y1909899D01*
X214459Y1909434D01*
X214574Y1909124D01*
X214804Y1908814D01*
X215073Y1908607D01*
X215341Y1908504D01*
X215609D01*
X215878Y1908607D01*
X216108Y1908762D01*
X216299Y1908969D01*
G01X219208Y1908504D02*
X217674D01*
Y1911604D01*
X219208D01*
G01X218594Y1910106D02*
X217674D01*
G01X220813Y1911087D02*
X221043Y1911397D01*
X221311Y1911552D01*
X221618Y1911604D01*
X222001Y1911501D01*
X222269Y1911242D01*
X222346Y1910932D01*
X222308Y1910622D01*
X222154Y1910364D01*
X221388Y1909847D01*
X221043Y1909486D01*
X220813Y1908969D01*
X220736Y1908504D01*
X222346D01*
G01X224641D02*
Y1911604D01*
X224181Y1910984D01*
G01Y1908504D02*
X225101D01*
G01X199015Y1981930D02*
Y2015530D01*
G01X219366Y1998230D02*
X217126D01*
G01X218339Y1996605D02*
Y1999855D01*
G01X219845Y2038038D02*
X217605D01*
G01X218818Y2036413D02*
Y2039663D01*
G01X198420Y2026588D02*
Y2060188D01*
G01X197454Y2067283D02*
X197224Y2067438D01*
X196956Y2067541D01*
X196649D01*
X196304Y2067386D01*
X196036Y2067128D01*
X195844Y2066818D01*
X195691Y2066301D01*
X195653Y2065836D01*
X195729Y2065371D01*
X195844Y2065061D01*
X196074Y2064751D01*
X196343Y2064544D01*
X196611Y2064441D01*
X196879D01*
X197148Y2064544D01*
X197378Y2064699D01*
X197569Y2064906D01*
G01X200478Y2064441D02*
X198944D01*
Y2067541D01*
X200478D01*
G01X199864Y2066043D02*
X198944D01*
G01X202083Y2067024D02*
X202313Y2067334D01*
X202581Y2067489D01*
X202888Y2067541D01*
X203271Y2067438D01*
X203539Y2067179D01*
X203616Y2066869D01*
X203578Y2066559D01*
X203424Y2066301D01*
X202658Y2065784D01*
X202313Y2065423D01*
X202083Y2064906D01*
X202006Y2064441D01*
X203616D01*
G01X206371D02*
Y2067541D01*
X204953Y2065319D01*
X206869D01*
G01X225500Y-122000D02*
Y-130000D01*
G01X223200Y-122000D02*
X227800D01*
G01X233500Y-124667D02*
Y-130000D01*
G01Y-122533D02*
X233300Y-122400D01*
Y-122133D01*
X233500Y-122000D01*
X233700Y-122133D01*
Y-122400D01*
X233500Y-122533D01*
G01X239800Y-130000D02*
Y-124667D01*
G01Y-126000D02*
X240200Y-125333D01*
X240800Y-124800D01*
X241600Y-124667D01*
X242300Y-124800D01*
X242900Y-125333D01*
X243200Y-126267D01*
Y-130000D01*
G01X251300D02*
Y-124667D01*
G01Y-125600D02*
X250900Y-125067D01*
X250300Y-124800D01*
X249600Y-124667D01*
X248900Y-124933D01*
X248300Y-125467D01*
X247900Y-126267D01*
X247700Y-127333D01*
X247900Y-128400D01*
X248300Y-129200D01*
X248900Y-129733D01*
X249600Y-130000D01*
X250300Y-129867D01*
X250900Y-129467D01*
X251300Y-128934D01*
G01X238356Y694796D02*
Y697896D01*
X239276D01*
X239583Y697741D01*
X239813Y697379D01*
X239890Y696966D01*
X239813Y696553D01*
X239621Y696243D01*
X239276Y696088D01*
X238356D01*
G01X241456Y694796D02*
Y697896D01*
X242415D01*
X242721Y697741D01*
X242913Y697534D01*
X242990Y697121D01*
X242913Y696708D01*
X242683Y696449D01*
X242415Y696294D01*
X241456D01*
G01X242415D02*
X242990Y694796D01*
G01X246090D02*
X244556D01*
Y697896D01*
X246090D01*
G01X245476Y696398D02*
X244556D01*
G01X247618Y695209D02*
X247925Y694951D01*
X248270Y694796D01*
X248576D01*
X248883Y694951D01*
X249113Y695209D01*
X249228Y695571D01*
X249151Y695933D01*
X248960Y696243D01*
X248615Y696449D01*
X248155Y696553D01*
X247886Y696759D01*
X247771Y697121D01*
X247848Y697483D01*
X248040Y697741D01*
X248308Y697896D01*
X248576D01*
X248845Y697793D01*
X249075Y697534D01*
G01X250718Y695209D02*
X251025Y694951D01*
X251370Y694796D01*
X251676D01*
X251983Y694951D01*
X252213Y695209D01*
X252328Y695571D01*
X252251Y695933D01*
X252060Y696243D01*
X251715Y696449D01*
X251255Y696553D01*
X250986Y696759D01*
X250871Y697121D01*
X250948Y697483D01*
X251140Y697741D01*
X251408Y697896D01*
X251676D01*
X251945Y697793D01*
X252175Y697534D01*
G01X254125Y695829D02*
X255121D01*
G01X256995Y694796D02*
Y697896D01*
X258451D01*
G01X257915Y696398D02*
X256995D01*
G01X260363Y697896D02*
X261283D01*
G01X260823D02*
Y694796D01*
G01X260363D02*
X261283D01*
G01X263923Y697896D02*
Y694796D01*
G01X263041Y697896D02*
X264805D01*
G01X220315Y776230D02*
X220085Y776385D01*
X219817Y776488D01*
X219510D01*
X219165Y776333D01*
X218897Y776075D01*
X218705Y775765D01*
X218552Y775248D01*
X218514Y774783D01*
X218590Y774318D01*
X218705Y774008D01*
X218935Y773698D01*
X219204Y773491D01*
X219472Y773388D01*
X219740D01*
X220009Y773491D01*
X220239Y773646D01*
X220430Y773853D01*
G01X223339Y773388D02*
X221805D01*
Y776488D01*
X223339D01*
G01X222725Y774990D02*
X221805D01*
G01X225672Y773388D02*
Y776488D01*
X225212Y775868D01*
G01Y773388D02*
X226132D01*
G01X228772Y776488D02*
X228465Y776385D01*
X228235Y776126D01*
X228082Y775816D01*
X227967Y775403D01*
X227929Y774938D01*
X227967Y774473D01*
X228082Y774060D01*
X228235Y773750D01*
X228465Y773491D01*
X228772Y773388D01*
X229079Y773491D01*
X229309Y773750D01*
X229462Y774060D01*
X229577Y774473D01*
X229615Y774938D01*
X229577Y775403D01*
X229462Y775816D01*
X229309Y776126D01*
X229079Y776385D01*
X228772Y776488D01*
G01X220303Y867801D02*
Y870901D01*
X221223D01*
X221530Y870746D01*
X221760Y870384D01*
X221837Y869971D01*
X221760Y869558D01*
X221568Y869248D01*
X221223Y869093D01*
X220303D01*
G01X223403Y867801D02*
Y870901D01*
X224362D01*
X224668Y870746D01*
X224860Y870539D01*
X224937Y870126D01*
X224860Y869713D01*
X224630Y869454D01*
X224362Y869299D01*
X223403D01*
G01X224362D02*
X224937Y867801D01*
G01X228037D02*
X226503D01*
Y870901D01*
X228037D01*
G01X227423Y869403D02*
X226503D01*
G01X229565Y868214D02*
X229872Y867956D01*
X230217Y867801D01*
X230523D01*
X230830Y867956D01*
X231060Y868214D01*
X231175Y868576D01*
X231098Y868938D01*
X230907Y869248D01*
X230562Y869454D01*
X230102Y869558D01*
X229833Y869764D01*
X229718Y870126D01*
X229795Y870488D01*
X229987Y870746D01*
X230255Y870901D01*
X230523D01*
X230792Y870798D01*
X231022Y870539D01*
G01X232665Y868214D02*
X232972Y867956D01*
X233317Y867801D01*
X233623D01*
X233930Y867956D01*
X234160Y868214D01*
X234275Y868576D01*
X234198Y868938D01*
X234007Y869248D01*
X233662Y869454D01*
X233202Y869558D01*
X232933Y869764D01*
X232818Y870126D01*
X232895Y870488D01*
X233087Y870746D01*
X233355Y870901D01*
X233623D01*
X233892Y870798D01*
X234122Y870539D01*
G01X236072Y868834D02*
X237068D01*
G01X238942Y867801D02*
Y870901D01*
X240398D01*
G01X239862Y869403D02*
X238942D01*
G01X242310Y870901D02*
X243230D01*
G01X242770D02*
Y867801D01*
G01X242310D02*
X243230D01*
G01X245870Y870901D02*
Y867801D01*
G01X244988Y870901D02*
X246752D01*
G01X225165Y940954D02*
X222925D01*
G01X224138Y939329D02*
Y942579D01*
G01X224958Y949371D02*
X224728Y949526D01*
X224460Y949629D01*
X224153D01*
X223808Y949474D01*
X223540Y949216D01*
X223348Y948906D01*
X223195Y948389D01*
X223157Y947924D01*
X223233Y947459D01*
X223348Y947149D01*
X223578Y946839D01*
X223847Y946632D01*
X224115Y946529D01*
X224383D01*
X224652Y946632D01*
X224882Y946787D01*
X225073Y946994D01*
G01X227982Y946529D02*
X226448D01*
Y949629D01*
X227982D01*
G01X227368Y948131D02*
X226448D01*
G01X230315Y946529D02*
Y949629D01*
X229855Y949009D01*
G01Y946529D02*
X230775D01*
G01X232687Y949112D02*
X232917Y949422D01*
X233185Y949577D01*
X233492Y949629D01*
X233875Y949526D01*
X234143Y949267D01*
X234220Y948957D01*
X234182Y948647D01*
X234028Y948389D01*
X233262Y947872D01*
X232917Y947511D01*
X232687Y946994D01*
X232610Y946529D01*
X234220D01*
G01X226420Y1033145D02*
X224180D01*
G01X225393Y1031520D02*
Y1034770D01*
G01X235988Y1045433D02*
Y1048533D01*
X236908D01*
X237215Y1048378D01*
X237445Y1048016D01*
X237522Y1047603D01*
X237445Y1047190D01*
X237253Y1046880D01*
X236908Y1046725D01*
X235988D01*
G01X239088Y1045433D02*
Y1048533D01*
X240047D01*
X240353Y1048378D01*
X240545Y1048171D01*
X240622Y1047758D01*
X240545Y1047345D01*
X240315Y1047086D01*
X240047Y1046931D01*
X239088D01*
G01X240047D02*
X240622Y1045433D01*
G01X243722D02*
X242188D01*
Y1048533D01*
X243722D01*
G01X243108Y1047035D02*
X242188D01*
G01X245250Y1045846D02*
X245557Y1045588D01*
X245902Y1045433D01*
X246208D01*
X246515Y1045588D01*
X246745Y1045846D01*
X246860Y1046208D01*
X246783Y1046570D01*
X246592Y1046880D01*
X246247Y1047086D01*
X245787Y1047190D01*
X245518Y1047396D01*
X245403Y1047758D01*
X245480Y1048120D01*
X245672Y1048378D01*
X245940Y1048533D01*
X246208D01*
X246477Y1048430D01*
X246707Y1048171D01*
G01X248350Y1045846D02*
X248657Y1045588D01*
X249002Y1045433D01*
X249308D01*
X249615Y1045588D01*
X249845Y1045846D01*
X249960Y1046208D01*
X249883Y1046570D01*
X249692Y1046880D01*
X249347Y1047086D01*
X248887Y1047190D01*
X248618Y1047396D01*
X248503Y1047758D01*
X248580Y1048120D01*
X248772Y1048378D01*
X249040Y1048533D01*
X249308D01*
X249577Y1048430D01*
X249807Y1048171D01*
G01X251757Y1046466D02*
X252753D01*
G01X254627Y1045433D02*
Y1048533D01*
X256083D01*
G01X255547Y1047035D02*
X254627D01*
G01X257995Y1048533D02*
X258915D01*
G01X258455D02*
Y1045433D01*
G01X257995D02*
X258915D01*
G01X261555Y1048533D02*
Y1045433D01*
G01X260673Y1048533D02*
X262437D01*
G01X229283Y1393684D02*
Y1396784D01*
X230203D01*
X230510Y1396629D01*
X230740Y1396267D01*
X230817Y1395854D01*
X230740Y1395441D01*
X230548Y1395131D01*
X230203Y1394976D01*
X229283D01*
G01X232383Y1393684D02*
Y1396784D01*
X233342D01*
X233648Y1396629D01*
X233840Y1396422D01*
X233917Y1396009D01*
X233840Y1395596D01*
X233610Y1395337D01*
X233342Y1395182D01*
X232383D01*
G01X233342D02*
X233917Y1393684D01*
G01X237017D02*
X235483D01*
Y1396784D01*
X237017D01*
G01X236403Y1395286D02*
X235483D01*
G01X238545Y1394097D02*
X238852Y1393839D01*
X239197Y1393684D01*
X239503D01*
X239810Y1393839D01*
X240040Y1394097D01*
X240155Y1394459D01*
X240078Y1394821D01*
X239887Y1395131D01*
X239542Y1395337D01*
X239082Y1395441D01*
X238813Y1395647D01*
X238698Y1396009D01*
X238775Y1396371D01*
X238967Y1396629D01*
X239235Y1396784D01*
X239503D01*
X239772Y1396681D01*
X240002Y1396422D01*
G01X241645Y1394097D02*
X241952Y1393839D01*
X242297Y1393684D01*
X242603D01*
X242910Y1393839D01*
X243140Y1394097D01*
X243255Y1394459D01*
X243178Y1394821D01*
X242987Y1395131D01*
X242642Y1395337D01*
X242182Y1395441D01*
X241913Y1395647D01*
X241798Y1396009D01*
X241875Y1396371D01*
X242067Y1396629D01*
X242335Y1396784D01*
X242603D01*
X242872Y1396681D01*
X243102Y1396422D01*
G01X245052Y1394717D02*
X246048D01*
G01X247922Y1393684D02*
Y1396784D01*
X249378D01*
G01X248842Y1395286D02*
X247922D01*
G01X251290Y1396784D02*
X252210D01*
G01X251750D02*
Y1393684D01*
G01X251290D02*
X252210D01*
G01X254850Y1396784D02*
Y1393684D01*
G01X253968Y1396784D02*
X255732D01*
G01X234561Y1569356D02*
Y1572456D01*
X235481D01*
X235788Y1572301D01*
X236018Y1571939D01*
X236095Y1571526D01*
X236018Y1571113D01*
X235826Y1570803D01*
X235481Y1570648D01*
X234561D01*
G01X237661Y1569356D02*
Y1572456D01*
X238620D01*
X238926Y1572301D01*
X239118Y1572094D01*
X239195Y1571681D01*
X239118Y1571268D01*
X238888Y1571009D01*
X238620Y1570854D01*
X237661D01*
G01X238620D02*
X239195Y1569356D01*
G01X242295D02*
X240761D01*
Y1572456D01*
X242295D01*
G01X241681Y1570958D02*
X240761D01*
G01X243823Y1569769D02*
X244130Y1569511D01*
X244475Y1569356D01*
X244781D01*
X245088Y1569511D01*
X245318Y1569769D01*
X245433Y1570131D01*
X245356Y1570493D01*
X245165Y1570803D01*
X244820Y1571009D01*
X244360Y1571113D01*
X244091Y1571319D01*
X243976Y1571681D01*
X244053Y1572043D01*
X244245Y1572301D01*
X244513Y1572456D01*
X244781D01*
X245050Y1572353D01*
X245280Y1572094D01*
G01X246923Y1569769D02*
X247230Y1569511D01*
X247575Y1569356D01*
X247881D01*
X248188Y1569511D01*
X248418Y1569769D01*
X248533Y1570131D01*
X248456Y1570493D01*
X248265Y1570803D01*
X247920Y1571009D01*
X247460Y1571113D01*
X247191Y1571319D01*
X247076Y1571681D01*
X247153Y1572043D01*
X247345Y1572301D01*
X247613Y1572456D01*
X247881D01*
X248150Y1572353D01*
X248380Y1572094D01*
G01X250330Y1570389D02*
X251326D01*
G01X253200Y1569356D02*
Y1572456D01*
X254656D01*
G01X254120Y1570958D02*
X253200D01*
G01X256568Y1572456D02*
X257488D01*
G01X257028D02*
Y1569356D01*
G01X256568D02*
X257488D01*
G01X260128Y1572456D02*
Y1569356D01*
G01X259246Y1572456D02*
X261010D01*
G01X239996Y1744063D02*
Y1747163D01*
X240916D01*
X241223Y1747008D01*
X241453Y1746646D01*
X241530Y1746233D01*
X241453Y1745820D01*
X241261Y1745510D01*
X240916Y1745355D01*
X239996D01*
G01X243096Y1744063D02*
Y1747163D01*
X244055D01*
X244361Y1747008D01*
X244553Y1746801D01*
X244630Y1746388D01*
X244553Y1745975D01*
X244323Y1745716D01*
X244055Y1745561D01*
X243096D01*
G01X244055D02*
X244630Y1744063D01*
G01X247730D02*
X246196D01*
Y1747163D01*
X247730D01*
G01X247116Y1745665D02*
X246196D01*
G01X249258Y1744476D02*
X249565Y1744218D01*
X249910Y1744063D01*
X250216D01*
X250523Y1744218D01*
X250753Y1744476D01*
X250868Y1744838D01*
X250791Y1745200D01*
X250600Y1745510D01*
X250255Y1745716D01*
X249795Y1745820D01*
X249526Y1746026D01*
X249411Y1746388D01*
X249488Y1746750D01*
X249680Y1747008D01*
X249948Y1747163D01*
X250216D01*
X250485Y1747060D01*
X250715Y1746801D01*
G01X252358Y1744476D02*
X252665Y1744218D01*
X253010Y1744063D01*
X253316D01*
X253623Y1744218D01*
X253853Y1744476D01*
X253968Y1744838D01*
X253891Y1745200D01*
X253700Y1745510D01*
X253355Y1745716D01*
X252895Y1745820D01*
X252626Y1746026D01*
X252511Y1746388D01*
X252588Y1746750D01*
X252780Y1747008D01*
X253048Y1747163D01*
X253316D01*
X253585Y1747060D01*
X253815Y1746801D01*
G01X255765Y1745096D02*
X256761D01*
G01X258635Y1744063D02*
Y1747163D01*
X260091D01*
G01X259555Y1745665D02*
X258635D01*
G01X262003Y1747163D02*
X262923D01*
G01X262463D02*
Y1744063D01*
G01X262003D02*
X262923D01*
G01X265563Y1747163D02*
Y1744063D01*
G01X264681Y1747163D02*
X266445D01*
G01X259200Y122623D02*
Y125723D01*
X260159D01*
X260465Y125568D01*
X260657Y125361D01*
X260734Y124948D01*
X260657Y124535D01*
X260427Y124276D01*
X260159Y124121D01*
X259200D01*
G01X260159D02*
X260734Y122623D01*
G01X263067D02*
Y125723D01*
X262607Y125103D01*
G01Y122623D02*
X263527D01*
G01X266167D02*
Y125723D01*
X265707Y125103D01*
G01Y122623D02*
X266627D01*
G01X269267D02*
Y125723D01*
X268807Y125103D01*
G01Y122623D02*
X269727D01*
G01X266210Y126628D02*
X260010D01*
Y129828D01*
X266210D01*
Y126628D01*
G01X258104Y109215D02*
Y112315D01*
X259063D01*
X259369Y112160D01*
X259561Y111953D01*
X259638Y111540D01*
X259561Y111127D01*
X259331Y110868D01*
X259063Y110713D01*
X258104D01*
G01X259063D02*
X259638Y109215D01*
G01X261971D02*
Y112315D01*
X261511Y111695D01*
G01Y109215D02*
X262431D01*
G01X265071D02*
Y112315D01*
X264611Y111695D01*
G01Y109215D02*
X265531D01*
G01X267443Y111798D02*
X267673Y112108D01*
X267941Y112263D01*
X268248Y112315D01*
X268631Y112212D01*
X268899Y111953D01*
X268976Y111643D01*
X268938Y111333D01*
X268784Y111075D01*
X268018Y110558D01*
X267673Y110197D01*
X267443Y109680D01*
X267366Y109215D01*
X268976D01*
G01X266454Y113959D02*
X260254D01*
Y117159D01*
X266454D01*
Y113959D01*
G01X261486Y149739D02*
Y155939D01*
X264686D01*
Y149739D01*
X261486D01*
G01X265820D02*
Y155939D01*
X269020D01*
Y149739D01*
X265820D01*
G01X261556Y159112D02*
X261401Y158882D01*
X261298Y158614D01*
Y158307D01*
X261453Y157962D01*
X261711Y157694D01*
X262021Y157502D01*
X262538Y157349D01*
X263003Y157311D01*
X263468Y157387D01*
X263778Y157502D01*
X264088Y157732D01*
X264295Y158001D01*
X264398Y158269D01*
Y158537D01*
X264295Y158806D01*
X264140Y159036D01*
X263933Y159227D01*
G01X264398Y161369D02*
X261298D01*
X261918Y160909D01*
G01X264398D02*
Y161829D01*
G01Y164929D02*
X261298D01*
X263520Y163511D01*
Y165427D01*
G01X264586Y152839D02*
X261586D01*
G01X265752Y159358D02*
X265597Y159128D01*
X265494Y158860D01*
Y158553D01*
X265649Y158208D01*
X265907Y157940D01*
X266217Y157748D01*
X266734Y157595D01*
X267199Y157557D01*
X267664Y157633D01*
X267974Y157748D01*
X268284Y157978D01*
X268491Y158247D01*
X268594Y158515D01*
Y158783D01*
X268491Y159052D01*
X268336Y159282D01*
X268129Y159473D01*
G01X268594Y161615D02*
X265494D01*
X266114Y161155D01*
G01X268594D02*
Y162075D01*
G01X267974Y163872D02*
X268336Y164102D01*
X268542Y164408D01*
X268594Y164753D01*
X268542Y165060D01*
X268284Y165367D01*
X267974Y165558D01*
X267664Y165597D01*
X267302Y165520D01*
X267044Y165252D01*
X266941Y164983D01*
Y164638D01*
G01Y164983D02*
X266786Y165213D01*
X266527Y165405D01*
X266217Y165482D01*
X265907Y165405D01*
X265649Y165213D01*
X265494Y164868D01*
X265546Y164523D01*
X265752Y164178D01*
G01X268920Y152839D02*
X265920D01*
G01X264807Y456200D02*
Y459300D01*
X265766D01*
X266072Y459145D01*
X266264Y458938D01*
X266341Y458525D01*
X266264Y458112D01*
X266034Y457853D01*
X265766Y457698D01*
X264807D01*
G01X265766D02*
X266341Y456200D01*
G01X268674D02*
Y459300D01*
X268214Y458680D01*
G01Y456200D02*
X269134D01*
G01X271774D02*
Y459300D01*
X271314Y458680D01*
G01Y456200D02*
X272234D01*
G01X274146Y457492D02*
X274414Y457853D01*
X274644Y458060D01*
X274951Y458163D01*
X275219Y458060D01*
X275411Y457853D01*
X275564Y457543D01*
X275602Y457182D01*
X275564Y456872D01*
X275411Y456562D01*
X275181Y456303D01*
X274912Y456200D01*
X274606Y456303D01*
X274337Y456613D01*
X274184Y457078D01*
X274146Y457595D01*
X274222Y458267D01*
X274337Y458628D01*
X274529Y458990D01*
X274797Y459248D01*
X275066Y459300D01*
X275334Y459197D01*
X275526Y458938D01*
G01X260743Y477444D02*
Y480544D01*
X261702D01*
X262008Y480389D01*
X262200Y480182D01*
X262277Y479769D01*
X262200Y479356D01*
X261970Y479097D01*
X261702Y478942D01*
X260743D01*
G01X261702D02*
X262277Y477444D01*
G01X264610D02*
Y480544D01*
X264150Y479924D01*
G01Y477444D02*
X265070D01*
G01X267710D02*
Y480544D01*
X267250Y479924D01*
G01Y477444D02*
X268170D01*
G01X269967Y477909D02*
X270197Y477651D01*
X270465Y477496D01*
X270810Y477444D01*
X271155Y477547D01*
X271423Y477754D01*
X271615Y478116D01*
X271653Y478529D01*
X271577Y478942D01*
X271385Y479201D01*
X271117Y479407D01*
X270848Y479459D01*
X270580Y479407D01*
X270235Y479201D01*
X270350Y480544D01*
X271385D01*
G01X262338Y509257D02*
X262183Y509027D01*
X262080Y508759D01*
Y508452D01*
X262235Y508107D01*
X262493Y507839D01*
X262803Y507647D01*
X263320Y507494D01*
X263785Y507456D01*
X264250Y507532D01*
X264560Y507647D01*
X264870Y507877D01*
X265077Y508146D01*
X265180Y508414D01*
Y508682D01*
X265077Y508951D01*
X264922Y509181D01*
X264715Y509372D01*
G01X262597Y510786D02*
X262287Y511016D01*
X262132Y511284D01*
X262080Y511591D01*
X262183Y511974D01*
X262442Y512242D01*
X262752Y512319D01*
X263062Y512281D01*
X263320Y512127D01*
X263837Y511361D01*
X264198Y511016D01*
X264715Y510786D01*
X265180Y510709D01*
Y512319D01*
G01Y514614D02*
X265128Y514882D01*
X264973Y515189D01*
X264715Y515381D01*
X264353Y515457D01*
X263992Y515381D01*
X263682Y515151D01*
X263527Y514806D01*
Y514422D01*
X263423Y514192D01*
X263165Y514001D01*
X262803Y513924D01*
X262442Y514039D01*
X262183Y514307D01*
X262080Y514614D01*
X262183Y514921D01*
X262442Y515189D01*
X262803Y515304D01*
X263165Y515227D01*
X263423Y515036D01*
X263527Y514806D01*
Y514422D01*
X263682Y514077D01*
X263992Y513847D01*
X264353Y513771D01*
X264715Y513847D01*
X264973Y514039D01*
X265128Y514346D01*
X265180Y514614D01*
G01X266016Y502494D02*
X263016D01*
G01X262916Y499394D02*
Y505594D01*
X266116D01*
Y499394D01*
X262916D01*
G01X263737Y805150D02*
Y808250D01*
X264696D01*
X265002Y808095D01*
X265194Y807888D01*
X265271Y807475D01*
X265194Y807062D01*
X264964Y806803D01*
X264696Y806648D01*
X263737D01*
G01X264696D02*
X265271Y805150D01*
G01X267604D02*
Y808250D01*
X267144Y807630D01*
G01Y805150D02*
X268064D01*
G01X269976Y807733D02*
X270206Y808043D01*
X270474Y808198D01*
X270781Y808250D01*
X271164Y808147D01*
X271432Y807888D01*
X271509Y807578D01*
X271471Y807268D01*
X271317Y807010D01*
X270551Y806493D01*
X270206Y806132D01*
X269976Y805615D01*
X269899Y805150D01*
X271509D01*
G01X273804Y808250D02*
X273497Y808147D01*
X273267Y807888D01*
X273114Y807578D01*
X272999Y807165D01*
X272961Y806700D01*
X272999Y806235D01*
X273114Y805822D01*
X273267Y805512D01*
X273497Y805253D01*
X273804Y805150D01*
X274111Y805253D01*
X274341Y805512D01*
X274494Y805822D01*
X274609Y806235D01*
X274647Y806700D01*
X274609Y807165D01*
X274494Y807578D01*
X274341Y807888D01*
X274111Y808147D01*
X273804Y808250D01*
G01X259209Y826039D02*
Y829139D01*
X260168D01*
X260474Y828984D01*
X260666Y828777D01*
X260743Y828364D01*
X260666Y827951D01*
X260436Y827692D01*
X260168Y827537D01*
X259209D01*
G01X260168D02*
X260743Y826039D01*
G01X263076D02*
Y829139D01*
X262616Y828519D01*
G01Y826039D02*
X263536D01*
G01X266176D02*
Y829139D01*
X265716Y828519D01*
G01Y826039D02*
X266636D01*
G01X268624Y826401D02*
X268893Y826142D01*
X269199Y826039D01*
X269506Y826142D01*
X269774Y826452D01*
X269966Y826917D01*
X270043Y827382D01*
Y827951D01*
X269966Y828416D01*
X269774Y828829D01*
X269544Y829036D01*
X269276Y829139D01*
X268969Y829036D01*
X268739Y828829D01*
X268586Y828519D01*
X268509Y828106D01*
X268586Y827744D01*
X268778Y827382D01*
X269008Y827176D01*
X269276Y827124D01*
X269583Y827227D01*
X269813Y827486D01*
X270043Y827951D01*
G01X265700Y822004D02*
X259500D01*
Y825204D01*
X265700D01*
Y822004D01*
G01X265860Y810570D02*
X259660D01*
Y813770D01*
X265860D01*
Y810570D01*
G01X265681Y852818D02*
X262681D01*
G01X262581Y849718D02*
Y855918D01*
X265781D01*
Y849718D01*
X262581D01*
G01X266775Y859485D02*
X266620Y859255D01*
X266517Y858987D01*
Y858680D01*
X266672Y858335D01*
X266930Y858067D01*
X267240Y857875D01*
X267757Y857722D01*
X268222Y857684D01*
X268687Y857760D01*
X268997Y857875D01*
X269307Y858105D01*
X269514Y858374D01*
X269617Y858642D01*
Y858910D01*
X269514Y859179D01*
X269359Y859409D01*
X269152Y859600D01*
G01X269617Y862202D02*
X266517D01*
X268739Y860784D01*
Y862700D01*
G01X269617Y864842D02*
X266517D01*
X267137Y864382D01*
G01X269617D02*
Y865302D01*
G01X261945Y859556D02*
X261790Y859326D01*
X261687Y859058D01*
Y858751D01*
X261842Y858406D01*
X262100Y858138D01*
X262410Y857946D01*
X262927Y857793D01*
X263392Y857755D01*
X263857Y857831D01*
X264167Y857946D01*
X264477Y858176D01*
X264684Y858445D01*
X264787Y858713D01*
Y858981D01*
X264684Y859250D01*
X264529Y859480D01*
X264322Y859671D01*
G01X264787Y862273D02*
X261687D01*
X263909Y860855D01*
Y862771D01*
G01X262204Y864185D02*
X261894Y864415D01*
X261739Y864683D01*
X261687Y864990D01*
X261790Y865373D01*
X262049Y865641D01*
X262359Y865718D01*
X262669Y865680D01*
X262927Y865526D01*
X263444Y864760D01*
X263805Y864415D01*
X264322Y864185D01*
X264787Y864108D01*
Y865718D01*
G01X265937Y1203031D02*
X265782Y1202801D01*
X265679Y1202533D01*
Y1202226D01*
X265834Y1201881D01*
X266092Y1201613D01*
X266402Y1201421D01*
X266919Y1201268D01*
X267384Y1201230D01*
X267849Y1201306D01*
X268159Y1201421D01*
X268469Y1201651D01*
X268676Y1201920D01*
X268779Y1202188D01*
Y1202456D01*
X268676Y1202725D01*
X268521Y1202955D01*
X268314Y1203146D01*
G01Y1204445D02*
X268572Y1204675D01*
X268727Y1204943D01*
X268779Y1205288D01*
X268676Y1205633D01*
X268469Y1205901D01*
X268107Y1206093D01*
X267694Y1206131D01*
X267281Y1206055D01*
X267022Y1205863D01*
X266816Y1205595D01*
X266764Y1205326D01*
X266816Y1205058D01*
X267022Y1204713D01*
X265679Y1204828D01*
Y1205863D01*
G01X268314Y1207545D02*
X268572Y1207775D01*
X268727Y1208043D01*
X268779Y1208388D01*
X268676Y1208733D01*
X268469Y1209001D01*
X268107Y1209193D01*
X267694Y1209231D01*
X267281Y1209155D01*
X267022Y1208963D01*
X266816Y1208695D01*
X266764Y1208426D01*
X266816Y1208158D01*
X267022Y1207813D01*
X265679Y1207928D01*
Y1208963D01*
G01X268694Y1196889D02*
X265694D01*
G01X265594Y1193789D02*
Y1199989D01*
X268794D01*
Y1193789D01*
X265594D01*
G01X260865Y1203175D02*
X260710Y1202945D01*
X260607Y1202677D01*
Y1202370D01*
X260762Y1202025D01*
X261020Y1201757D01*
X261330Y1201565D01*
X261847Y1201412D01*
X262312Y1201374D01*
X262777Y1201450D01*
X263087Y1201565D01*
X263397Y1201795D01*
X263604Y1202064D01*
X263707Y1202332D01*
Y1202600D01*
X263604Y1202869D01*
X263449Y1203099D01*
X263242Y1203290D01*
G01Y1204589D02*
X263500Y1204819D01*
X263655Y1205087D01*
X263707Y1205432D01*
X263604Y1205777D01*
X263397Y1206045D01*
X263035Y1206237D01*
X262622Y1206275D01*
X262209Y1206199D01*
X261950Y1206007D01*
X261744Y1205739D01*
X261692Y1205470D01*
X261744Y1205202D01*
X261950Y1204857D01*
X260607Y1204972D01*
Y1206007D01*
G01X262415Y1207804D02*
X262054Y1208072D01*
X261847Y1208302D01*
X261744Y1208609D01*
X261847Y1208877D01*
X262054Y1209069D01*
X262364Y1209222D01*
X262725Y1209260D01*
X263035Y1209222D01*
X263345Y1209069D01*
X263604Y1208839D01*
X263707Y1208570D01*
X263604Y1208264D01*
X263294Y1207995D01*
X262829Y1207842D01*
X262312Y1207804D01*
X261640Y1207880D01*
X261279Y1207995D01*
X260917Y1208187D01*
X260659Y1208455D01*
X260607Y1208724D01*
X260710Y1208992D01*
X260969Y1209184D01*
G01X264059Y1196889D02*
X261059D01*
G01X260959Y1193789D02*
Y1199989D01*
X264159D01*
Y1193789D01*
X260959D01*
G01X338582Y127165D02*
G03I-31496J0D01*
G01X270343Y149739D02*
Y155939D01*
X273543D01*
Y149739D01*
X270343D01*
G01X274923D02*
Y155939D01*
X278123D01*
Y149739D01*
X274923D01*
G01X270095Y159454D02*
X269940Y159224D01*
X269837Y158956D01*
Y158649D01*
X269992Y158304D01*
X270250Y158036D01*
X270560Y157844D01*
X271077Y157691D01*
X271542Y157653D01*
X272007Y157729D01*
X272317Y157844D01*
X272627Y158074D01*
X272834Y158343D01*
X272937Y158611D01*
Y158879D01*
X272834Y159148D01*
X272679Y159378D01*
X272472Y159569D01*
G01X272937Y161711D02*
X269837D01*
X270457Y161251D01*
G01X272937D02*
Y162171D01*
G01X270354Y164083D02*
X270044Y164313D01*
X269889Y164581D01*
X269837Y164888D01*
X269940Y165271D01*
X270199Y165539D01*
X270509Y165616D01*
X270819Y165578D01*
X271077Y165424D01*
X271594Y164658D01*
X271955Y164313D01*
X272472Y164083D01*
X272937Y164006D01*
Y165616D01*
G01X273443Y152839D02*
X270443D01*
G01X274148Y159551D02*
X273993Y159321D01*
X273890Y159053D01*
Y158746D01*
X274045Y158401D01*
X274303Y158133D01*
X274613Y157941D01*
X275130Y157788D01*
X275595Y157750D01*
X276060Y157826D01*
X276370Y157941D01*
X276680Y158171D01*
X276887Y158440D01*
X276990Y158708D01*
Y158976D01*
X276887Y159245D01*
X276732Y159475D01*
X276525Y159666D01*
G01X276990Y161808D02*
X273890D01*
X274510Y161348D01*
G01X276990D02*
Y162268D01*
G01Y164908D02*
X273890D01*
X274510Y164448D01*
G01X276990D02*
Y165368D01*
G01X278023Y152839D02*
X275023D01*
G01X278217Y254964D02*
Y248764D01*
X275017D01*
Y254964D01*
X278217D01*
G01X282793D02*
Y248764D01*
X279593D01*
Y254964D01*
X282793D01*
G01X273847Y258964D02*
Y248764D01*
X269247D01*
Y258964D01*
X273847D01*
G01X274385Y263933D02*
X274230Y263703D01*
X274127Y263435D01*
Y263128D01*
X274282Y262783D01*
X274540Y262515D01*
X274850Y262323D01*
X275367Y262170D01*
X275832Y262132D01*
X276297Y262208D01*
X276607Y262323D01*
X276917Y262553D01*
X277124Y262822D01*
X277227Y263090D01*
Y263358D01*
X277124Y263627D01*
X276969Y263857D01*
X276762Y264048D01*
G01X276865Y265538D02*
X277124Y265807D01*
X277227Y266113D01*
X277124Y266420D01*
X276814Y266688D01*
X276349Y266880D01*
X275884Y266957D01*
X275315D01*
X274850Y266880D01*
X274437Y266688D01*
X274230Y266458D01*
X274127Y266190D01*
X274230Y265883D01*
X274437Y265653D01*
X274747Y265500D01*
X275160Y265423D01*
X275522Y265500D01*
X275884Y265692D01*
X276090Y265922D01*
X276142Y266190D01*
X276039Y266497D01*
X275780Y266727D01*
X275315Y266957D01*
G01X275117Y251864D02*
X278117D01*
G01X279420Y263933D02*
X279265Y263703D01*
X279162Y263435D01*
Y263128D01*
X279317Y262783D01*
X279575Y262515D01*
X279885Y262323D01*
X280402Y262170D01*
X280867Y262132D01*
X281332Y262208D01*
X281642Y262323D01*
X281952Y262553D01*
X282159Y262822D01*
X282262Y263090D01*
Y263358D01*
X282159Y263627D01*
X282004Y263857D01*
X281797Y264048D01*
G01X282262Y266190D02*
X279162D01*
X279782Y265730D01*
G01X282262D02*
Y266650D01*
G01X279162Y269290D02*
X279265Y268983D01*
X279524Y268753D01*
X279834Y268600D01*
X280247Y268485D01*
X280712Y268447D01*
X281177Y268485D01*
X281590Y268600D01*
X281900Y268753D01*
X282159Y268983D01*
X282262Y269290D01*
X282159Y269597D01*
X281900Y269827D01*
X281590Y269980D01*
X281177Y270095D01*
X280712Y270133D01*
X280247Y270095D01*
X279834Y269980D01*
X279524Y269827D01*
X279265Y269597D01*
X279162Y269290D01*
G01X279693Y251864D02*
X282693D01*
G01X269852Y263933D02*
X269697Y263703D01*
X269594Y263435D01*
Y263128D01*
X269749Y262783D01*
X270007Y262515D01*
X270317Y262323D01*
X270834Y262170D01*
X271299Y262132D01*
X271764Y262208D01*
X272074Y262323D01*
X272384Y262553D01*
X272591Y262822D01*
X272694Y263090D01*
Y263358D01*
X272591Y263627D01*
X272436Y263857D01*
X272229Y264048D01*
G01X272694Y266190D02*
X272642Y266458D01*
X272487Y266765D01*
X272229Y266957D01*
X271867Y267033D01*
X271506Y266957D01*
X271196Y266727D01*
X271041Y266382D01*
Y265998D01*
X270937Y265768D01*
X270679Y265577D01*
X270317Y265500D01*
X269956Y265615D01*
X269697Y265883D01*
X269594Y266190D01*
X269697Y266497D01*
X269956Y266765D01*
X270317Y266880D01*
X270679Y266803D01*
X270937Y266612D01*
X271041Y266382D01*
Y265998D01*
X271196Y265653D01*
X271506Y265423D01*
X271867Y265347D01*
X272229Y265423D01*
X272487Y265615D01*
X272642Y265922D01*
X272694Y266190D01*
G01X273847Y253864D02*
X269247D01*
G01X278978Y334423D02*
X278823Y334193D01*
X278720Y333925D01*
Y333618D01*
X278875Y333273D01*
X279133Y333005D01*
X279443Y332813D01*
X279960Y332660D01*
X280425Y332622D01*
X280890Y332698D01*
X281200Y332813D01*
X281510Y333043D01*
X281717Y333312D01*
X281820Y333580D01*
Y333848D01*
X281717Y334117D01*
X281562Y334347D01*
X281355Y334538D01*
G01X279237Y335952D02*
X278927Y336182D01*
X278772Y336450D01*
X278720Y336757D01*
X278823Y337140D01*
X279082Y337408D01*
X279392Y337485D01*
X279702Y337447D01*
X279960Y337293D01*
X280477Y336527D01*
X280838Y336182D01*
X281355Y335952D01*
X281820Y335875D01*
Y337485D01*
G01Y339780D02*
X278720D01*
X279340Y339320D01*
G01X281820D02*
Y340240D01*
G01X282574Y328092D02*
X279574D01*
G01X279474Y324992D02*
Y331192D01*
X282674D01*
Y324992D01*
X279474D01*
G01X288811Y334280D02*
X288656Y334050D01*
X288553Y333782D01*
Y333475D01*
X288708Y333130D01*
X288966Y332862D01*
X289276Y332670D01*
X289793Y332517D01*
X290258Y332479D01*
X290723Y332555D01*
X291033Y332670D01*
X291343Y332900D01*
X291550Y333169D01*
X291653Y333437D01*
Y333705D01*
X291550Y333974D01*
X291395Y334204D01*
X291188Y334395D01*
G01X291653Y336537D02*
X288553D01*
X289173Y336077D01*
G01X291653D02*
Y336997D01*
G01X291291Y338985D02*
X291550Y339254D01*
X291653Y339560D01*
X291550Y339867D01*
X291240Y340135D01*
X290775Y340327D01*
X290310Y340404D01*
X289741D01*
X289276Y340327D01*
X288863Y340135D01*
X288656Y339905D01*
X288553Y339637D01*
X288656Y339330D01*
X288863Y339100D01*
X289173Y338947D01*
X289586Y338870D01*
X289948Y338947D01*
X290310Y339139D01*
X290516Y339369D01*
X290568Y339637D01*
X290465Y339944D01*
X290206Y340174D01*
X289741Y340404D01*
G01X291395Y328092D02*
X288395D01*
G01X288295Y324992D02*
Y331192D01*
X291495D01*
Y324992D01*
X288295D01*
G01X284004Y334139D02*
X283849Y333909D01*
X283746Y333641D01*
Y333334D01*
X283901Y332989D01*
X284159Y332721D01*
X284469Y332529D01*
X284986Y332376D01*
X285451Y332338D01*
X285916Y332414D01*
X286226Y332529D01*
X286536Y332759D01*
X286743Y333028D01*
X286846Y333296D01*
Y333564D01*
X286743Y333833D01*
X286588Y334063D01*
X286381Y334254D01*
G01X284263Y335668D02*
X283953Y335898D01*
X283798Y336166D01*
X283746Y336473D01*
X283849Y336856D01*
X284108Y337124D01*
X284418Y337201D01*
X284728Y337163D01*
X284986Y337009D01*
X285503Y336243D01*
X285864Y335898D01*
X286381Y335668D01*
X286846Y335591D01*
Y337201D01*
G01X283746Y339496D02*
X283849Y339189D01*
X284108Y338959D01*
X284418Y338806D01*
X284831Y338691D01*
X285296Y338653D01*
X285761Y338691D01*
X286174Y338806D01*
X286484Y338959D01*
X286743Y339189D01*
X286846Y339496D01*
X286743Y339803D01*
X286484Y340033D01*
X286174Y340186D01*
X285761Y340301D01*
X285296Y340339D01*
X284831Y340301D01*
X284418Y340186D01*
X284108Y340033D01*
X283849Y339803D01*
X283746Y339496D01*
G01X287013Y328092D02*
X284013D01*
G01X283913Y324992D02*
Y331192D01*
X287113D01*
Y324992D01*
X283913D01*
G01X289873Y439993D02*
X289718Y439763D01*
X289615Y439495D01*
Y439188D01*
X289770Y438843D01*
X290028Y438575D01*
X290338Y438383D01*
X290855Y438230D01*
X291320Y438192D01*
X291785Y438268D01*
X292095Y438383D01*
X292405Y438613D01*
X292612Y438882D01*
X292715Y439150D01*
Y439418D01*
X292612Y439687D01*
X292457Y439917D01*
X292250Y440108D01*
G01X292715Y442250D02*
X289615D01*
X290235Y441790D01*
G01X292715D02*
Y442710D01*
G01Y445273D02*
X292043Y445350D01*
X291475Y445465D01*
X290958Y445618D01*
X290390Y445810D01*
X289615Y446117D01*
Y444583D01*
G01X289502Y427440D02*
X292502D01*
G01X292602Y430540D02*
Y424340D01*
X289402D01*
Y430540D01*
X292602D01*
G01X284758Y439993D02*
X284603Y439763D01*
X284500Y439495D01*
Y439188D01*
X284655Y438843D01*
X284913Y438575D01*
X285223Y438383D01*
X285740Y438230D01*
X286205Y438192D01*
X286670Y438268D01*
X286980Y438383D01*
X287290Y438613D01*
X287497Y438882D01*
X287600Y439150D01*
Y439418D01*
X287497Y439687D01*
X287342Y439917D01*
X287135Y440108D01*
G01X287600Y442250D02*
X284500D01*
X285120Y441790D01*
G01X287600D02*
Y442710D01*
G01X286308Y444622D02*
X285947Y444890D01*
X285740Y445120D01*
X285637Y445427D01*
X285740Y445695D01*
X285947Y445887D01*
X286257Y446040D01*
X286618Y446078D01*
X286928Y446040D01*
X287238Y445887D01*
X287497Y445657D01*
X287600Y445388D01*
X287497Y445082D01*
X287187Y444813D01*
X286722Y444660D01*
X286205Y444622D01*
X285533Y444698D01*
X285172Y444813D01*
X284810Y445005D01*
X284552Y445273D01*
X284500Y445542D01*
X284603Y445810D01*
X284862Y446002D01*
G01X285165Y427440D02*
X288165D01*
G01X288265Y430540D02*
Y424340D01*
X285065D01*
Y430540D01*
X288265D01*
G01X280154Y439993D02*
X279999Y439763D01*
X279896Y439495D01*
Y439188D01*
X280051Y438843D01*
X280309Y438575D01*
X280619Y438383D01*
X281136Y438230D01*
X281601Y438192D01*
X282066Y438268D01*
X282376Y438383D01*
X282686Y438613D01*
X282893Y438882D01*
X282996Y439150D01*
Y439418D01*
X282893Y439687D01*
X282738Y439917D01*
X282531Y440108D01*
G01X282996Y442250D02*
X279896D01*
X280516Y441790D01*
G01X282996D02*
Y442710D01*
G01X282531Y444507D02*
X282789Y444737D01*
X282944Y445005D01*
X282996Y445350D01*
X282893Y445695D01*
X282686Y445963D01*
X282324Y446155D01*
X281911Y446193D01*
X281498Y446117D01*
X281239Y445925D01*
X281033Y445657D01*
X280981Y445388D01*
X281033Y445120D01*
X281239Y444775D01*
X279896Y444890D01*
Y445925D01*
G01X283869Y434540D02*
Y424340D01*
X279269D01*
Y434540D01*
X283869D01*
G01Y429440D02*
X279269D01*
G01X273636Y461499D02*
X267436D01*
Y464699D01*
X273636D01*
Y461499D01*
G01X338582Y477165D02*
G03I-31496J0D01*
G01X273563Y472077D02*
X267363D01*
Y475277D01*
X273563D01*
Y472077D01*
G01X268544Y490278D02*
Y493378D01*
G01X270154D02*
Y490278D01*
G01Y491828D02*
X268544D01*
G01X271797Y490640D02*
X272066Y490381D01*
X272372Y490278D01*
X272679Y490381D01*
X272947Y490691D01*
X273139Y491156D01*
X273216Y491621D01*
Y492190D01*
X273139Y492655D01*
X272947Y493068D01*
X272717Y493275D01*
X272449Y493378D01*
X272142Y493275D01*
X271912Y493068D01*
X271759Y492758D01*
X271682Y492345D01*
X271759Y491983D01*
X271951Y491621D01*
X272181Y491415D01*
X272449Y491363D01*
X272756Y491466D01*
X272986Y491725D01*
X273216Y492190D01*
G01X271858Y509115D02*
X271703Y508885D01*
X271600Y508617D01*
Y508310D01*
X271755Y507965D01*
X272013Y507697D01*
X272323Y507505D01*
X272840Y507352D01*
X273305Y507314D01*
X273770Y507390D01*
X274080Y507505D01*
X274390Y507735D01*
X274597Y508004D01*
X274700Y508272D01*
Y508540D01*
X274597Y508809D01*
X274442Y509039D01*
X274235Y509230D01*
G01X272117Y510644D02*
X271807Y510874D01*
X271652Y511142D01*
X271600Y511449D01*
X271703Y511832D01*
X271962Y512100D01*
X272272Y512177D01*
X272582Y512139D01*
X272840Y511985D01*
X273357Y511219D01*
X273718Y510874D01*
X274235Y510644D01*
X274700Y510567D01*
Y512177D01*
G01X273408Y513744D02*
X273047Y514012D01*
X272840Y514242D01*
X272737Y514549D01*
X272840Y514817D01*
X273047Y515009D01*
X273357Y515162D01*
X273718Y515200D01*
X274028Y515162D01*
X274338Y515009D01*
X274597Y514779D01*
X274700Y514510D01*
X274597Y514204D01*
X274287Y513935D01*
X273822Y513782D01*
X273305Y513744D01*
X272633Y513820D01*
X272272Y513935D01*
X271910Y514127D01*
X271652Y514395D01*
X271600Y514664D01*
X271703Y514932D01*
X271962Y515124D01*
G01X274905Y502494D02*
X271905D01*
G01X271805Y499394D02*
Y505594D01*
X275005D01*
Y499394D01*
X271805D01*
G01X267013Y509186D02*
X266858Y508956D01*
X266755Y508688D01*
Y508381D01*
X266910Y508036D01*
X267168Y507768D01*
X267478Y507576D01*
X267995Y507423D01*
X268460Y507385D01*
X268925Y507461D01*
X269235Y507576D01*
X269545Y507806D01*
X269752Y508075D01*
X269855Y508343D01*
Y508611D01*
X269752Y508880D01*
X269597Y509110D01*
X269390Y509301D01*
G01X267272Y510715D02*
X266962Y510945D01*
X266807Y511213D01*
X266755Y511520D01*
X266858Y511903D01*
X267117Y512171D01*
X267427Y512248D01*
X267737Y512210D01*
X267995Y512056D01*
X268512Y511290D01*
X268873Y510945D01*
X269390Y510715D01*
X269855Y510638D01*
Y512248D01*
G01Y514466D02*
X269183Y514543D01*
X268615Y514658D01*
X268098Y514811D01*
X267530Y515003D01*
X266755Y515310D01*
Y513776D01*
G01X270438Y502494D02*
X267438D01*
G01X267338Y499394D02*
Y505594D01*
X270538D01*
Y499394D01*
X267338D01*
G01X276687Y508829D02*
X276532Y508599D01*
X276429Y508331D01*
Y508024D01*
X276584Y507679D01*
X276842Y507411D01*
X277152Y507219D01*
X277669Y507066D01*
X278134Y507028D01*
X278599Y507104D01*
X278909Y507219D01*
X279219Y507449D01*
X279426Y507718D01*
X279529Y507986D01*
Y508254D01*
X279426Y508523D01*
X279271Y508753D01*
X279064Y508944D01*
G01X276946Y510358D02*
X276636Y510588D01*
X276481Y510856D01*
X276429Y511163D01*
X276532Y511546D01*
X276791Y511814D01*
X277101Y511891D01*
X277411Y511853D01*
X277669Y511699D01*
X278186Y510933D01*
X278547Y510588D01*
X279064Y510358D01*
X279529Y510281D01*
Y511891D01*
G01X279064Y513343D02*
X279322Y513573D01*
X279477Y513841D01*
X279529Y514186D01*
X279426Y514531D01*
X279219Y514799D01*
X278857Y514991D01*
X278444Y515029D01*
X278031Y514953D01*
X277772Y514761D01*
X277566Y514493D01*
X277514Y514224D01*
X277566Y513956D01*
X277772Y513611D01*
X276429Y513726D01*
Y514761D01*
G01X279276Y502494D02*
X276276D01*
G01X276176Y499394D02*
Y505594D01*
X279376D01*
Y499394D01*
X276176D01*
G01X289484Y602062D02*
X292484D01*
G01X292584Y605162D02*
Y598962D01*
X289384D01*
Y605162D01*
X292584D01*
G01X287648Y609162D02*
Y598962D01*
X283048D01*
Y609162D01*
X287648D01*
G01Y604062D02*
X283048D01*
G01X289048Y614443D02*
X288893Y614213D01*
X288790Y613945D01*
Y613638D01*
X288945Y613293D01*
X289203Y613025D01*
X289513Y612833D01*
X290030Y612680D01*
X290495Y612642D01*
X290960Y612718D01*
X291270Y612833D01*
X291580Y613063D01*
X291787Y613332D01*
X291890Y613600D01*
Y613868D01*
X291787Y614137D01*
X291632Y614367D01*
X291425Y614558D01*
G01X289307Y615972D02*
X288997Y616202D01*
X288842Y616470D01*
X288790Y616777D01*
X288893Y617160D01*
X289152Y617428D01*
X289462Y617505D01*
X289772Y617467D01*
X290030Y617313D01*
X290547Y616547D01*
X290908Y616202D01*
X291425Y615972D01*
X291890Y615895D01*
Y617505D01*
G01X291270Y618957D02*
X291632Y619187D01*
X291838Y619493D01*
X291890Y619838D01*
X291838Y620145D01*
X291580Y620452D01*
X291270Y620643D01*
X290960Y620682D01*
X290598Y620605D01*
X290340Y620337D01*
X290237Y620068D01*
Y619723D01*
G01Y620068D02*
X290082Y620298D01*
X289823Y620490D01*
X289513Y620567D01*
X289203Y620490D01*
X288945Y620298D01*
X288790Y619953D01*
X288842Y619608D01*
X289048Y619263D01*
G01X284042Y614443D02*
X283887Y614213D01*
X283784Y613945D01*
Y613638D01*
X283939Y613293D01*
X284197Y613025D01*
X284507Y612833D01*
X285024Y612680D01*
X285489Y612642D01*
X285954Y612718D01*
X286264Y612833D01*
X286574Y613063D01*
X286781Y613332D01*
X286884Y613600D01*
Y613868D01*
X286781Y614137D01*
X286626Y614367D01*
X286419Y614558D01*
G01X284301Y615972D02*
X283991Y616202D01*
X283836Y616470D01*
X283784Y616777D01*
X283887Y617160D01*
X284146Y617428D01*
X284456Y617505D01*
X284766Y617467D01*
X285024Y617313D01*
X285541Y616547D01*
X285902Y616202D01*
X286419Y615972D01*
X286884Y615895D01*
Y617505D01*
G01X284301Y619072D02*
X283991Y619302D01*
X283836Y619570D01*
X283784Y619877D01*
X283887Y620260D01*
X284146Y620528D01*
X284456Y620605D01*
X284766Y620567D01*
X285024Y620413D01*
X285541Y619647D01*
X285902Y619302D01*
X286419Y619072D01*
X286884Y618995D01*
Y620605D01*
G01X283401Y663335D02*
X283246Y663105D01*
X283143Y662837D01*
Y662530D01*
X283298Y662185D01*
X283556Y661917D01*
X283866Y661725D01*
X284383Y661572D01*
X284848Y661534D01*
X285313Y661610D01*
X285623Y661725D01*
X285933Y661955D01*
X286140Y662224D01*
X286243Y662492D01*
Y662760D01*
X286140Y663029D01*
X285985Y663259D01*
X285778Y663450D01*
G01X285623Y664749D02*
X285985Y664979D01*
X286191Y665285D01*
X286243Y665630D01*
X286191Y665937D01*
X285933Y666244D01*
X285623Y666435D01*
X285313Y666474D01*
X284951Y666397D01*
X284693Y666129D01*
X284590Y665860D01*
Y665515D01*
G01Y665860D02*
X284435Y666090D01*
X284176Y666282D01*
X283866Y666359D01*
X283556Y666282D01*
X283298Y666090D01*
X283143Y665745D01*
X283195Y665400D01*
X283401Y665055D01*
G01X283660Y667964D02*
X283350Y668194D01*
X283195Y668462D01*
X283143Y668769D01*
X283246Y669152D01*
X283505Y669420D01*
X283815Y669497D01*
X284125Y669459D01*
X284383Y669305D01*
X284900Y668539D01*
X285261Y668194D01*
X285778Y667964D01*
X286243Y667887D01*
Y669497D01*
G01X284840Y677699D02*
X281840D01*
G01X281740Y674599D02*
Y680799D01*
X284940D01*
Y674599D01*
X281740D01*
G01X278280Y663336D02*
X278125Y663106D01*
X278022Y662838D01*
Y662531D01*
X278177Y662186D01*
X278435Y661918D01*
X278745Y661726D01*
X279262Y661573D01*
X279727Y661535D01*
X280192Y661611D01*
X280502Y661726D01*
X280812Y661956D01*
X281019Y662225D01*
X281122Y662493D01*
Y662761D01*
X281019Y663030D01*
X280864Y663260D01*
X280657Y663451D01*
G01X280502Y664750D02*
X280864Y664980D01*
X281070Y665286D01*
X281122Y665631D01*
X281070Y665938D01*
X280812Y666245D01*
X280502Y666436D01*
X280192Y666475D01*
X279830Y666398D01*
X279572Y666130D01*
X279469Y665861D01*
Y665516D01*
G01Y665861D02*
X279314Y666091D01*
X279055Y666283D01*
X278745Y666360D01*
X278435Y666283D01*
X278177Y666091D01*
X278022Y665746D01*
X278074Y665401D01*
X278280Y665056D01*
G01X280502Y667850D02*
X280864Y668080D01*
X281070Y668386D01*
X281122Y668731D01*
X281070Y669038D01*
X280812Y669345D01*
X280502Y669536D01*
X280192Y669575D01*
X279830Y669498D01*
X279572Y669230D01*
X279469Y668961D01*
Y668616D01*
G01Y668961D02*
X279314Y669191D01*
X279055Y669383D01*
X278745Y669460D01*
X278435Y669383D01*
X278177Y669191D01*
X278022Y668846D01*
X278074Y668501D01*
X278280Y668156D01*
G01X280455Y677699D02*
X277455D01*
G01X277355Y674599D02*
Y680799D01*
X280555D01*
Y674599D01*
X277355D01*
G01X273622Y663621D02*
X273467Y663391D01*
X273364Y663123D01*
Y662816D01*
X273519Y662471D01*
X273777Y662203D01*
X274087Y662011D01*
X274604Y661858D01*
X275069Y661820D01*
X275534Y661896D01*
X275844Y662011D01*
X276154Y662241D01*
X276361Y662510D01*
X276464Y662778D01*
Y663046D01*
X276361Y663315D01*
X276206Y663545D01*
X275999Y663736D01*
G01X275844Y665035D02*
X276206Y665265D01*
X276412Y665571D01*
X276464Y665916D01*
X276412Y666223D01*
X276154Y666530D01*
X275844Y666721D01*
X275534Y666760D01*
X275172Y666683D01*
X274914Y666415D01*
X274811Y666146D01*
Y665801D01*
G01Y666146D02*
X274656Y666376D01*
X274397Y666568D01*
X274087Y666645D01*
X273777Y666568D01*
X273519Y666376D01*
X273364Y666031D01*
X273416Y665686D01*
X273622Y665341D01*
G01X276464Y669438D02*
X273364D01*
X275586Y668020D01*
Y669936D01*
G01X276014Y677699D02*
X273014D01*
G01X272914Y674599D02*
Y680799D01*
X276114D01*
Y674599D01*
X272914D01*
G01X268901Y663621D02*
X268746Y663391D01*
X268643Y663123D01*
Y662816D01*
X268798Y662471D01*
X269056Y662203D01*
X269366Y662011D01*
X269883Y661858D01*
X270348Y661820D01*
X270813Y661896D01*
X271123Y662011D01*
X271433Y662241D01*
X271640Y662510D01*
X271743Y662778D01*
Y663046D01*
X271640Y663315D01*
X271485Y663545D01*
X271278Y663736D01*
G01X271123Y665035D02*
X271485Y665265D01*
X271691Y665571D01*
X271743Y665916D01*
X271691Y666223D01*
X271433Y666530D01*
X271123Y666721D01*
X270813Y666760D01*
X270451Y666683D01*
X270193Y666415D01*
X270090Y666146D01*
Y665801D01*
G01Y666146D02*
X269935Y666376D01*
X269676Y666568D01*
X269366Y666645D01*
X269056Y666568D01*
X268798Y666376D01*
X268643Y666031D01*
X268695Y665686D01*
X268901Y665341D01*
G01X271278Y668135D02*
X271536Y668365D01*
X271691Y668633D01*
X271743Y668978D01*
X271640Y669323D01*
X271433Y669591D01*
X271071Y669783D01*
X270658Y669821D01*
X270245Y669745D01*
X269986Y669553D01*
X269780Y669285D01*
X269728Y669016D01*
X269780Y668748D01*
X269986Y668403D01*
X268643Y668518D01*
Y669553D01*
G01X271609Y677699D02*
X268609D01*
G01X268509Y674599D02*
Y680799D01*
X271709D01*
Y674599D01*
X268509D01*
G01X277517Y764942D02*
X277362Y764712D01*
X277259Y764444D01*
Y764137D01*
X277414Y763792D01*
X277672Y763524D01*
X277982Y763332D01*
X278499Y763179D01*
X278964Y763141D01*
X279429Y763217D01*
X279739Y763332D01*
X280049Y763562D01*
X280256Y763831D01*
X280359Y764099D01*
Y764367D01*
X280256Y764636D01*
X280101Y764866D01*
X279894Y765057D01*
G01X279739Y766356D02*
X280101Y766586D01*
X280307Y766892D01*
X280359Y767237D01*
X280307Y767544D01*
X280049Y767851D01*
X279739Y768042D01*
X279429Y768081D01*
X279067Y768004D01*
X278809Y767736D01*
X278706Y767467D01*
Y767122D01*
G01Y767467D02*
X278551Y767697D01*
X278292Y767889D01*
X277982Y767966D01*
X277672Y767889D01*
X277414Y767697D01*
X277259Y767352D01*
X277311Y767007D01*
X277517Y766662D01*
G01X277259Y770299D02*
X277362Y769992D01*
X277621Y769762D01*
X277931Y769609D01*
X278344Y769494D01*
X278809Y769456D01*
X279274Y769494D01*
X279687Y769609D01*
X279997Y769762D01*
X280256Y769992D01*
X280359Y770299D01*
X280256Y770606D01*
X279997Y770836D01*
X279687Y770989D01*
X279274Y771104D01*
X278809Y771142D01*
X278344Y771104D01*
X277931Y770989D01*
X277621Y770836D01*
X277362Y770606D01*
X277259Y770299D01*
G01X276684Y777136D02*
X279684D01*
G01X279784Y780236D02*
Y774036D01*
X276584D01*
Y780236D01*
X279784D01*
G01X282616Y764942D02*
X282461Y764712D01*
X282358Y764444D01*
Y764137D01*
X282513Y763792D01*
X282771Y763524D01*
X283081Y763332D01*
X283598Y763179D01*
X284063Y763141D01*
X284528Y763217D01*
X284838Y763332D01*
X285148Y763562D01*
X285355Y763831D01*
X285458Y764099D01*
Y764367D01*
X285355Y764636D01*
X285200Y764866D01*
X284993Y765057D01*
G01X284838Y766356D02*
X285200Y766586D01*
X285406Y766892D01*
X285458Y767237D01*
X285406Y767544D01*
X285148Y767851D01*
X284838Y768042D01*
X284528Y768081D01*
X284166Y768004D01*
X283908Y767736D01*
X283805Y767467D01*
Y767122D01*
G01Y767467D02*
X283650Y767697D01*
X283391Y767889D01*
X283081Y767966D01*
X282771Y767889D01*
X282513Y767697D01*
X282358Y767352D01*
X282410Y767007D01*
X282616Y766662D01*
G01X285458Y770299D02*
X282358D01*
X282978Y769839D01*
G01X285458D02*
Y770759D01*
G01X281237Y777136D02*
X284237D01*
G01X284337Y780236D02*
Y774036D01*
X281137D01*
Y780236D01*
X284337D01*
G01X272442Y764942D02*
X272287Y764712D01*
X272184Y764444D01*
Y764137D01*
X272339Y763792D01*
X272597Y763524D01*
X272907Y763332D01*
X273424Y763179D01*
X273889Y763141D01*
X274354Y763217D01*
X274664Y763332D01*
X274974Y763562D01*
X275181Y763831D01*
X275284Y764099D01*
Y764367D01*
X275181Y764636D01*
X275026Y764866D01*
X274819Y765057D01*
G01X272701Y766471D02*
X272391Y766701D01*
X272236Y766969D01*
X272184Y767276D01*
X272287Y767659D01*
X272546Y767927D01*
X272856Y768004D01*
X273166Y767966D01*
X273424Y767812D01*
X273941Y767046D01*
X274302Y766701D01*
X274819Y766471D01*
X275284Y766394D01*
Y768004D01*
G01X274922Y769647D02*
X275181Y769916D01*
X275284Y770222D01*
X275181Y770529D01*
X274871Y770797D01*
X274406Y770989D01*
X273941Y771066D01*
X273372D01*
X272907Y770989D01*
X272494Y770797D01*
X272287Y770567D01*
X272184Y770299D01*
X272287Y769992D01*
X272494Y769762D01*
X272804Y769609D01*
X273217Y769532D01*
X273579Y769609D01*
X273941Y769801D01*
X274147Y770031D01*
X274199Y770299D01*
X274096Y770606D01*
X273837Y770836D01*
X273372Y771066D01*
G01X275414Y784236D02*
Y774036D01*
X270814D01*
Y784236D01*
X275414D01*
G01Y779136D02*
X270814D01*
G01X338582Y827165D02*
G03I-31496J0D01*
G01X279288Y852818D02*
X276288D01*
G01X276188Y849718D02*
Y855918D01*
X279388D01*
Y849718D01*
X276188D01*
G01X274805Y852818D02*
X271805D01*
G01X271705Y849718D02*
Y855918D01*
X274905D01*
Y849718D01*
X271705D01*
G01X270186Y852818D02*
X267186D01*
G01X267086Y849718D02*
Y855918D01*
X270286D01*
Y849718D01*
X267086D01*
G01X276826Y859343D02*
X276671Y859113D01*
X276568Y858845D01*
Y858538D01*
X276723Y858193D01*
X276981Y857925D01*
X277291Y857733D01*
X277808Y857580D01*
X278273Y857542D01*
X278738Y857618D01*
X279048Y857733D01*
X279358Y857963D01*
X279565Y858232D01*
X279668Y858500D01*
Y858768D01*
X279565Y859037D01*
X279410Y859267D01*
X279203Y859458D01*
G01X279048Y860757D02*
X279410Y860987D01*
X279616Y861293D01*
X279668Y861638D01*
X279616Y861945D01*
X279358Y862252D01*
X279048Y862443D01*
X278738Y862482D01*
X278376Y862405D01*
X278118Y862137D01*
X278015Y861868D01*
Y861523D01*
G01Y861868D02*
X277860Y862098D01*
X277601Y862290D01*
X277291Y862367D01*
X276981Y862290D01*
X276723Y862098D01*
X276568Y861753D01*
X276620Y861408D01*
X276826Y861063D01*
G01X279306Y864048D02*
X279565Y864317D01*
X279668Y864623D01*
X279565Y864930D01*
X279255Y865198D01*
X278790Y865390D01*
X278325Y865467D01*
X277756D01*
X277291Y865390D01*
X276878Y865198D01*
X276671Y864968D01*
X276568Y864700D01*
X276671Y864393D01*
X276878Y864163D01*
X277188Y864010D01*
X277601Y863933D01*
X277963Y864010D01*
X278325Y864202D01*
X278531Y864432D01*
X278583Y864700D01*
X278480Y865007D01*
X278221Y865237D01*
X277756Y865467D01*
G01X271777Y859485D02*
X271622Y859255D01*
X271519Y858987D01*
Y858680D01*
X271674Y858335D01*
X271932Y858067D01*
X272242Y857875D01*
X272759Y857722D01*
X273224Y857684D01*
X273689Y857760D01*
X273999Y857875D01*
X274309Y858105D01*
X274516Y858374D01*
X274619Y858642D01*
Y858910D01*
X274516Y859179D01*
X274361Y859409D01*
X274154Y859600D01*
G01X274619Y862202D02*
X271519D01*
X273741Y860784D01*
Y862700D01*
G01X271519Y864842D02*
X271622Y864535D01*
X271881Y864305D01*
X272191Y864152D01*
X272604Y864037D01*
X273069Y863999D01*
X273534Y864037D01*
X273947Y864152D01*
X274257Y864305D01*
X274516Y864535D01*
X274619Y864842D01*
X274516Y865149D01*
X274257Y865379D01*
X273947Y865532D01*
X273534Y865647D01*
X273069Y865685D01*
X272604Y865647D01*
X272191Y865532D01*
X271881Y865379D01*
X271622Y865149D01*
X271519Y864842D01*
G01X292794Y953961D02*
Y947761D01*
X289594D01*
Y953961D01*
X292794D01*
G01X288266Y957961D02*
Y947761D01*
X283666D01*
Y957961D01*
X288266D01*
G01X289694Y950861D02*
X292694D01*
G01X288266Y952861D02*
X283666D01*
G01X289085Y1006229D02*
X288930Y1005999D01*
X288827Y1005731D01*
Y1005424D01*
X288982Y1005079D01*
X289240Y1004811D01*
X289550Y1004619D01*
X290067Y1004466D01*
X290532Y1004428D01*
X290997Y1004504D01*
X291307Y1004619D01*
X291617Y1004849D01*
X291824Y1005118D01*
X291927Y1005386D01*
Y1005654D01*
X291824Y1005923D01*
X291669Y1006153D01*
X291462Y1006344D01*
G01X291927Y1008946D02*
X288827D01*
X291049Y1007528D01*
Y1009444D01*
G01X291927Y1011509D02*
X291255Y1011586D01*
X290687Y1011701D01*
X290170Y1011854D01*
X289602Y1012046D01*
X288827Y1012353D01*
Y1010819D01*
G01X291607Y1021457D02*
X288607D01*
G01X288507Y1018357D02*
Y1024557D01*
X291707D01*
Y1018357D01*
X288507D01*
G01X284036Y1006229D02*
X283881Y1005999D01*
X283778Y1005731D01*
Y1005424D01*
X283933Y1005079D01*
X284191Y1004811D01*
X284501Y1004619D01*
X285018Y1004466D01*
X285483Y1004428D01*
X285948Y1004504D01*
X286258Y1004619D01*
X286568Y1004849D01*
X286775Y1005118D01*
X286878Y1005386D01*
Y1005654D01*
X286775Y1005923D01*
X286620Y1006153D01*
X286413Y1006344D01*
G01X286878Y1008946D02*
X283778D01*
X286000Y1007528D01*
Y1009444D01*
G01X286878Y1011586D02*
X286826Y1011854D01*
X286671Y1012161D01*
X286413Y1012353D01*
X286051Y1012429D01*
X285690Y1012353D01*
X285380Y1012123D01*
X285225Y1011778D01*
Y1011394D01*
X285121Y1011164D01*
X284863Y1010973D01*
X284501Y1010896D01*
X284140Y1011011D01*
X283881Y1011279D01*
X283778Y1011586D01*
X283881Y1011893D01*
X284140Y1012161D01*
X284501Y1012276D01*
X284863Y1012199D01*
X285121Y1012008D01*
X285225Y1011778D01*
Y1011394D01*
X285380Y1011049D01*
X285690Y1010819D01*
X286051Y1010743D01*
X286413Y1010819D01*
X286671Y1011011D01*
X286826Y1011318D01*
X286878Y1011586D01*
G01X287166Y1021457D02*
X284166D01*
G01X284066Y1018357D02*
Y1024557D01*
X287266D01*
Y1018357D01*
X284066D01*
G01X279174Y1006301D02*
X279019Y1006071D01*
X278916Y1005803D01*
Y1005496D01*
X279071Y1005151D01*
X279329Y1004883D01*
X279639Y1004691D01*
X280156Y1004538D01*
X280621Y1004500D01*
X281086Y1004576D01*
X281396Y1004691D01*
X281706Y1004921D01*
X281913Y1005190D01*
X282016Y1005458D01*
Y1005726D01*
X281913Y1005995D01*
X281758Y1006225D01*
X281551Y1006416D01*
G01X282016Y1009018D02*
X278916D01*
X281138Y1007600D01*
Y1009516D01*
G01X281654Y1011006D02*
X281913Y1011275D01*
X282016Y1011581D01*
X281913Y1011888D01*
X281603Y1012156D01*
X281138Y1012348D01*
X280673Y1012425D01*
X280104D01*
X279639Y1012348D01*
X279226Y1012156D01*
X279019Y1011926D01*
X278916Y1011658D01*
X279019Y1011351D01*
X279226Y1011121D01*
X279536Y1010968D01*
X279949Y1010891D01*
X280311Y1010968D01*
X280673Y1011160D01*
X280879Y1011390D01*
X280931Y1011658D01*
X280828Y1011965D01*
X280569Y1012195D01*
X280104Y1012425D01*
G01X282624Y1021457D02*
X279624D01*
G01X279524Y1018357D02*
Y1024557D01*
X282724D01*
Y1018357D01*
X279524D01*
G01X286688Y1125851D02*
X289688D01*
G01X289788Y1128951D02*
Y1122751D01*
X286588D01*
Y1128951D01*
X289788D01*
G01X285258Y1132951D02*
Y1122751D01*
X280658D01*
Y1132951D01*
X285258D01*
G01Y1127851D02*
X280658D01*
G01X276520Y1202888D02*
X276365Y1202658D01*
X276262Y1202390D01*
Y1202083D01*
X276417Y1201738D01*
X276675Y1201470D01*
X276985Y1201278D01*
X277502Y1201125D01*
X277967Y1201087D01*
X278432Y1201163D01*
X278742Y1201278D01*
X279052Y1201508D01*
X279259Y1201777D01*
X279362Y1202045D01*
Y1202313D01*
X279259Y1202582D01*
X279104Y1202812D01*
X278897Y1203003D01*
G01Y1204302D02*
X279155Y1204532D01*
X279310Y1204800D01*
X279362Y1205145D01*
X279259Y1205490D01*
X279052Y1205758D01*
X278690Y1205950D01*
X278277Y1205988D01*
X277864Y1205912D01*
X277605Y1205720D01*
X277399Y1205452D01*
X277347Y1205183D01*
X277399Y1204915D01*
X277605Y1204570D01*
X276262Y1204685D01*
Y1205720D01*
G01X278742Y1207402D02*
X279104Y1207632D01*
X279310Y1207938D01*
X279362Y1208283D01*
X279310Y1208590D01*
X279052Y1208897D01*
X278742Y1209088D01*
X278432Y1209127D01*
X278070Y1209050D01*
X277812Y1208782D01*
X277709Y1208513D01*
Y1208168D01*
G01Y1208513D02*
X277554Y1208743D01*
X277295Y1208935D01*
X276985Y1209012D01*
X276675Y1208935D01*
X276417Y1208743D01*
X276262Y1208398D01*
X276314Y1208053D01*
X276520Y1207708D01*
G01X278307Y1196889D02*
X275307D01*
G01X275207Y1193789D02*
Y1199989D01*
X278407D01*
Y1193789D01*
X275207D01*
G01X271304Y1202960D02*
X271149Y1202730D01*
X271046Y1202462D01*
Y1202155D01*
X271201Y1201810D01*
X271459Y1201542D01*
X271769Y1201350D01*
X272286Y1201197D01*
X272751Y1201159D01*
X273216Y1201235D01*
X273526Y1201350D01*
X273836Y1201580D01*
X274043Y1201849D01*
X274146Y1202117D01*
Y1202385D01*
X274043Y1202654D01*
X273888Y1202884D01*
X273681Y1203075D01*
G01Y1204374D02*
X273939Y1204604D01*
X274094Y1204872D01*
X274146Y1205217D01*
X274043Y1205562D01*
X273836Y1205830D01*
X273474Y1206022D01*
X273061Y1206060D01*
X272648Y1205984D01*
X272389Y1205792D01*
X272183Y1205524D01*
X272131Y1205255D01*
X272183Y1204987D01*
X272389Y1204642D01*
X271046Y1204757D01*
Y1205792D01*
G01X274146Y1208777D02*
X271046D01*
X273268Y1207359D01*
Y1209275D01*
G01X273582Y1196889D02*
X270582D01*
G01X270482Y1193789D02*
Y1199989D01*
X273682D01*
Y1193789D01*
X270482D01*
G01X288053Y1289431D02*
X287898Y1289201D01*
X287795Y1288933D01*
Y1288626D01*
X287950Y1288281D01*
X288208Y1288013D01*
X288518Y1287821D01*
X289035Y1287668D01*
X289500Y1287630D01*
X289965Y1287706D01*
X290275Y1287821D01*
X290585Y1288051D01*
X290792Y1288320D01*
X290895Y1288588D01*
Y1288856D01*
X290792Y1289125D01*
X290637Y1289355D01*
X290430Y1289546D01*
G01Y1290845D02*
X290688Y1291075D01*
X290843Y1291343D01*
X290895Y1291688D01*
X290792Y1292033D01*
X290585Y1292301D01*
X290223Y1292493D01*
X289810Y1292531D01*
X289397Y1292455D01*
X289138Y1292263D01*
X288932Y1291995D01*
X288880Y1291726D01*
X288932Y1291458D01*
X289138Y1291113D01*
X287795Y1291228D01*
Y1292263D01*
G01X290895Y1294788D02*
X287795D01*
X288415Y1294328D01*
G01X290895D02*
Y1295248D01*
G01X282937Y1289431D02*
X282782Y1289201D01*
X282679Y1288933D01*
Y1288626D01*
X282834Y1288281D01*
X283092Y1288013D01*
X283402Y1287821D01*
X283919Y1287668D01*
X284384Y1287630D01*
X284849Y1287706D01*
X285159Y1287821D01*
X285469Y1288051D01*
X285676Y1288320D01*
X285779Y1288588D01*
Y1288856D01*
X285676Y1289125D01*
X285521Y1289355D01*
X285314Y1289546D01*
G01Y1290845D02*
X285572Y1291075D01*
X285727Y1291343D01*
X285779Y1291688D01*
X285676Y1292033D01*
X285469Y1292301D01*
X285107Y1292493D01*
X284694Y1292531D01*
X284281Y1292455D01*
X284022Y1292263D01*
X283816Y1291995D01*
X283764Y1291726D01*
X283816Y1291458D01*
X284022Y1291113D01*
X282679Y1291228D01*
Y1292263D01*
G01Y1294788D02*
X282782Y1294481D01*
X283041Y1294251D01*
X283351Y1294098D01*
X283764Y1293983D01*
X284229Y1293945D01*
X284694Y1293983D01*
X285107Y1294098D01*
X285417Y1294251D01*
X285676Y1294481D01*
X285779Y1294788D01*
X285676Y1295095D01*
X285417Y1295325D01*
X285107Y1295478D01*
X284694Y1295593D01*
X284229Y1295631D01*
X283764Y1295593D01*
X283351Y1295478D01*
X283041Y1295325D01*
X282782Y1295095D01*
X282679Y1294788D01*
G01X287710Y1300522D02*
X290710D01*
G01X290810Y1303622D02*
Y1297422D01*
X287610D01*
Y1303622D01*
X290810D01*
G01X286108Y1307622D02*
Y1297422D01*
X281508D01*
Y1307622D01*
X286108D01*
G01Y1302522D02*
X281508D01*
G01X338582Y1343504D02*
G03I-31496J0D01*
G01X284061Y1386399D02*
X283906Y1386169D01*
X283803Y1385901D01*
Y1385594D01*
X283958Y1385249D01*
X284216Y1384981D01*
X284526Y1384789D01*
X285043Y1384636D01*
X285508Y1384598D01*
X285973Y1384674D01*
X286283Y1384789D01*
X286593Y1385019D01*
X286800Y1385288D01*
X286903Y1385556D01*
Y1385824D01*
X286800Y1386093D01*
X286645Y1386323D01*
X286438Y1386514D01*
G01X285611Y1387928D02*
X285250Y1388196D01*
X285043Y1388426D01*
X284940Y1388733D01*
X285043Y1389001D01*
X285250Y1389193D01*
X285560Y1389346D01*
X285921Y1389384D01*
X286231Y1389346D01*
X286541Y1389193D01*
X286800Y1388963D01*
X286903Y1388694D01*
X286800Y1388388D01*
X286490Y1388119D01*
X286025Y1387966D01*
X285508Y1387928D01*
X284836Y1388004D01*
X284475Y1388119D01*
X284113Y1388311D01*
X283855Y1388579D01*
X283803Y1388848D01*
X283906Y1389116D01*
X284165Y1389308D01*
G01X283803Y1391756D02*
X283906Y1391449D01*
X284165Y1391219D01*
X284475Y1391066D01*
X284888Y1390951D01*
X285353Y1390913D01*
X285818Y1390951D01*
X286231Y1391066D01*
X286541Y1391219D01*
X286800Y1391449D01*
X286903Y1391756D01*
X286800Y1392063D01*
X286541Y1392293D01*
X286231Y1392446D01*
X285818Y1392561D01*
X285353Y1392599D01*
X284888Y1392561D01*
X284475Y1392446D01*
X284165Y1392293D01*
X283906Y1392063D01*
X283803Y1391756D01*
G01X285740Y1379917D02*
X282740D01*
G01X282640Y1376817D02*
Y1383017D01*
X285840D01*
Y1376817D01*
X282640D01*
G01X278669Y1386471D02*
X278514Y1386241D01*
X278411Y1385973D01*
Y1385666D01*
X278566Y1385321D01*
X278824Y1385053D01*
X279134Y1384861D01*
X279651Y1384708D01*
X280116Y1384670D01*
X280581Y1384746D01*
X280891Y1384861D01*
X281201Y1385091D01*
X281408Y1385360D01*
X281511Y1385628D01*
Y1385896D01*
X281408Y1386165D01*
X281253Y1386395D01*
X281046Y1386586D01*
G01X280219Y1388000D02*
X279858Y1388268D01*
X279651Y1388498D01*
X279548Y1388805D01*
X279651Y1389073D01*
X279858Y1389265D01*
X280168Y1389418D01*
X280529Y1389456D01*
X280839Y1389418D01*
X281149Y1389265D01*
X281408Y1389035D01*
X281511Y1388766D01*
X281408Y1388460D01*
X281098Y1388191D01*
X280633Y1388038D01*
X280116Y1388000D01*
X279444Y1388076D01*
X279083Y1388191D01*
X278721Y1388383D01*
X278463Y1388651D01*
X278411Y1388920D01*
X278514Y1389188D01*
X278773Y1389380D01*
G01X281511Y1391828D02*
X278411D01*
X279031Y1391368D01*
G01X281511D02*
Y1392288D01*
G01X281018Y1379916D02*
X278018D01*
G01X277918Y1376816D02*
Y1383016D01*
X281118D01*
Y1376816D01*
X277918D01*
G01X273176Y1386399D02*
X273021Y1386169D01*
X272918Y1385901D01*
Y1385594D01*
X273073Y1385249D01*
X273331Y1384981D01*
X273641Y1384789D01*
X274158Y1384636D01*
X274623Y1384598D01*
X275088Y1384674D01*
X275398Y1384789D01*
X275708Y1385019D01*
X275915Y1385288D01*
X276018Y1385556D01*
Y1385824D01*
X275915Y1386093D01*
X275760Y1386323D01*
X275553Y1386514D01*
G01X274726Y1387928D02*
X274365Y1388196D01*
X274158Y1388426D01*
X274055Y1388733D01*
X274158Y1389001D01*
X274365Y1389193D01*
X274675Y1389346D01*
X275036Y1389384D01*
X275346Y1389346D01*
X275656Y1389193D01*
X275915Y1388963D01*
X276018Y1388694D01*
X275915Y1388388D01*
X275605Y1388119D01*
X275140Y1387966D01*
X274623Y1387928D01*
X273951Y1388004D01*
X273590Y1388119D01*
X273228Y1388311D01*
X272970Y1388579D01*
X272918Y1388848D01*
X273021Y1389116D01*
X273280Y1389308D01*
G01X273435Y1391028D02*
X273125Y1391258D01*
X272970Y1391526D01*
X272918Y1391833D01*
X273021Y1392216D01*
X273280Y1392484D01*
X273590Y1392561D01*
X273900Y1392523D01*
X274158Y1392369D01*
X274675Y1391603D01*
X275036Y1391258D01*
X275553Y1391028D01*
X276018Y1390951D01*
Y1392561D01*
G01X276552Y1379916D02*
X273552D01*
G01X273452Y1376816D02*
Y1383016D01*
X276652D01*
Y1376816D01*
X273452D01*
G01X272079Y1379916D02*
X269079D01*
G01X268979Y1376816D02*
Y1383016D01*
X272179D01*
Y1376816D01*
X268979D01*
G01X282031Y1370171D02*
Y1373271D01*
G01X283641D02*
Y1370171D01*
G01Y1371721D02*
X282031D01*
G01X285093Y1370636D02*
X285323Y1370378D01*
X285591Y1370223D01*
X285936Y1370171D01*
X286281Y1370274D01*
X286549Y1370481D01*
X286741Y1370843D01*
X286779Y1371256D01*
X286703Y1371669D01*
X286511Y1371928D01*
X286243Y1372134D01*
X285974Y1372186D01*
X285706Y1372134D01*
X285361Y1371928D01*
X285476Y1373271D01*
X286511D01*
G01X267683Y1386543D02*
X267528Y1386313D01*
X267425Y1386045D01*
Y1385738D01*
X267580Y1385393D01*
X267838Y1385125D01*
X268148Y1384933D01*
X268665Y1384780D01*
X269130Y1384742D01*
X269595Y1384818D01*
X269905Y1384933D01*
X270215Y1385163D01*
X270422Y1385432D01*
X270525Y1385700D01*
Y1385968D01*
X270422Y1386237D01*
X270267Y1386467D01*
X270060Y1386658D01*
G01X269233Y1388072D02*
X268872Y1388340D01*
X268665Y1388570D01*
X268562Y1388877D01*
X268665Y1389145D01*
X268872Y1389337D01*
X269182Y1389490D01*
X269543Y1389528D01*
X269853Y1389490D01*
X270163Y1389337D01*
X270422Y1389107D01*
X270525Y1388838D01*
X270422Y1388532D01*
X270112Y1388263D01*
X269647Y1388110D01*
X269130Y1388072D01*
X268458Y1388148D01*
X268097Y1388263D01*
X267735Y1388455D01*
X267477Y1388723D01*
X267425Y1388992D01*
X267528Y1389260D01*
X267787Y1389452D01*
G01X269905Y1391057D02*
X270267Y1391287D01*
X270473Y1391593D01*
X270525Y1391938D01*
X270473Y1392245D01*
X270215Y1392552D01*
X269905Y1392743D01*
X269595Y1392782D01*
X269233Y1392705D01*
X268975Y1392437D01*
X268872Y1392168D01*
Y1391823D01*
G01Y1392168D02*
X268717Y1392398D01*
X268458Y1392590D01*
X268148Y1392667D01*
X267838Y1392590D01*
X267580Y1392398D01*
X267425Y1392053D01*
X267477Y1391708D01*
X267683Y1391363D01*
G01X274021Y1474062D02*
X277021D01*
G01X277121Y1477162D02*
Y1470962D01*
X273921D01*
Y1477162D01*
X277121D01*
G01X278490Y1474062D02*
X281490D01*
G01X281590Y1477162D02*
Y1470962D01*
X278390D01*
Y1477162D01*
X281590D01*
G01X272534Y1481162D02*
Y1470962D01*
X267934D01*
Y1481162D01*
X272534D01*
G01Y1476062D02*
X267934D01*
G01X273488Y1486587D02*
X273333Y1486357D01*
X273230Y1486089D01*
Y1485782D01*
X273385Y1485437D01*
X273643Y1485169D01*
X273953Y1484977D01*
X274470Y1484824D01*
X274935Y1484786D01*
X275400Y1484862D01*
X275710Y1484977D01*
X276020Y1485207D01*
X276227Y1485476D01*
X276330Y1485744D01*
Y1486012D01*
X276227Y1486281D01*
X276072Y1486511D01*
X275865Y1486702D01*
G01Y1488001D02*
X276123Y1488231D01*
X276278Y1488499D01*
X276330Y1488844D01*
X276227Y1489189D01*
X276020Y1489457D01*
X275658Y1489649D01*
X275245Y1489687D01*
X274832Y1489611D01*
X274573Y1489419D01*
X274367Y1489151D01*
X274315Y1488882D01*
X274367Y1488614D01*
X274573Y1488269D01*
X273230Y1488384D01*
Y1489419D01*
G01X276330Y1491944D02*
X276278Y1492212D01*
X276123Y1492519D01*
X275865Y1492711D01*
X275503Y1492787D01*
X275142Y1492711D01*
X274832Y1492481D01*
X274677Y1492136D01*
Y1491752D01*
X274573Y1491522D01*
X274315Y1491331D01*
X273953Y1491254D01*
X273592Y1491369D01*
X273333Y1491637D01*
X273230Y1491944D01*
X273333Y1492251D01*
X273592Y1492519D01*
X273953Y1492634D01*
X274315Y1492557D01*
X274573Y1492366D01*
X274677Y1492136D01*
Y1491752D01*
X274832Y1491407D01*
X275142Y1491177D01*
X275503Y1491101D01*
X275865Y1491177D01*
X276123Y1491369D01*
X276278Y1491676D01*
X276330Y1491944D01*
G01X279007Y1486587D02*
X278852Y1486357D01*
X278749Y1486089D01*
Y1485782D01*
X278904Y1485437D01*
X279162Y1485169D01*
X279472Y1484977D01*
X279989Y1484824D01*
X280454Y1484786D01*
X280919Y1484862D01*
X281229Y1484977D01*
X281539Y1485207D01*
X281746Y1485476D01*
X281849Y1485744D01*
Y1486012D01*
X281746Y1486281D01*
X281591Y1486511D01*
X281384Y1486702D01*
G01Y1488001D02*
X281642Y1488231D01*
X281797Y1488499D01*
X281849Y1488844D01*
X281746Y1489189D01*
X281539Y1489457D01*
X281177Y1489649D01*
X280764Y1489687D01*
X280351Y1489611D01*
X280092Y1489419D01*
X279886Y1489151D01*
X279834Y1488882D01*
X279886Y1488614D01*
X280092Y1488269D01*
X278749Y1488384D01*
Y1489419D01*
G01X281487Y1491292D02*
X281746Y1491561D01*
X281849Y1491867D01*
X281746Y1492174D01*
X281436Y1492442D01*
X280971Y1492634D01*
X280506Y1492711D01*
X279937D01*
X279472Y1492634D01*
X279059Y1492442D01*
X278852Y1492212D01*
X278749Y1491944D01*
X278852Y1491637D01*
X279059Y1491407D01*
X279369Y1491254D01*
X279782Y1491177D01*
X280144Y1491254D01*
X280506Y1491446D01*
X280712Y1491676D01*
X280764Y1491944D01*
X280661Y1492251D01*
X280402Y1492481D01*
X279937Y1492711D01*
G01X268169Y1486587D02*
X268014Y1486357D01*
X267911Y1486089D01*
Y1485782D01*
X268066Y1485437D01*
X268324Y1485169D01*
X268634Y1484977D01*
X269151Y1484824D01*
X269616Y1484786D01*
X270081Y1484862D01*
X270391Y1484977D01*
X270701Y1485207D01*
X270908Y1485476D01*
X271011Y1485744D01*
Y1486012D01*
X270908Y1486281D01*
X270753Y1486511D01*
X270546Y1486702D01*
G01Y1488001D02*
X270804Y1488231D01*
X270959Y1488499D01*
X271011Y1488844D01*
X270908Y1489189D01*
X270701Y1489457D01*
X270339Y1489649D01*
X269926Y1489687D01*
X269513Y1489611D01*
X269254Y1489419D01*
X269048Y1489151D01*
X268996Y1488882D01*
X269048Y1488614D01*
X269254Y1488269D01*
X267911Y1488384D01*
Y1489419D01*
G01X271011Y1491867D02*
X270339Y1491944D01*
X269771Y1492059D01*
X269254Y1492212D01*
X268686Y1492404D01*
X267911Y1492711D01*
Y1491177D01*
G01X289395Y1555290D02*
X289240Y1555060D01*
X289137Y1554792D01*
Y1554485D01*
X289292Y1554140D01*
X289550Y1553872D01*
X289860Y1553680D01*
X290377Y1553527D01*
X290842Y1553489D01*
X291307Y1553565D01*
X291617Y1553680D01*
X291927Y1553910D01*
X292134Y1554179D01*
X292237Y1554447D01*
Y1554715D01*
X292134Y1554984D01*
X291979Y1555214D01*
X291772Y1555405D01*
G01X292237Y1557470D02*
X291565Y1557547D01*
X290997Y1557662D01*
X290480Y1557815D01*
X289912Y1558007D01*
X289137Y1558314D01*
Y1556780D01*
G01Y1560647D02*
X289240Y1560340D01*
X289499Y1560110D01*
X289809Y1559957D01*
X290222Y1559842D01*
X290687Y1559804D01*
X291152Y1559842D01*
X291565Y1559957D01*
X291875Y1560110D01*
X292134Y1560340D01*
X292237Y1560647D01*
X292134Y1560954D01*
X291875Y1561184D01*
X291565Y1561337D01*
X291152Y1561452D01*
X290687Y1561490D01*
X290222Y1561452D01*
X289809Y1561337D01*
X289499Y1561184D01*
X289240Y1560954D01*
X289137Y1560647D01*
G01X292554Y1549026D02*
X289554D01*
G01X289454Y1545926D02*
Y1552126D01*
X292654D01*
Y1545926D01*
X289454D01*
G01X288251Y1639075D02*
X288096Y1638845D01*
X287993Y1638577D01*
Y1638270D01*
X288148Y1637925D01*
X288406Y1637657D01*
X288716Y1637465D01*
X289233Y1637312D01*
X289698Y1637274D01*
X290163Y1637350D01*
X290473Y1637465D01*
X290783Y1637695D01*
X290990Y1637964D01*
X291093Y1638232D01*
Y1638500D01*
X290990Y1638769D01*
X290835Y1638999D01*
X290628Y1639190D01*
G01X289801Y1640604D02*
X289440Y1640872D01*
X289233Y1641102D01*
X289130Y1641409D01*
X289233Y1641677D01*
X289440Y1641869D01*
X289750Y1642022D01*
X290111Y1642060D01*
X290421Y1642022D01*
X290731Y1641869D01*
X290990Y1641639D01*
X291093Y1641370D01*
X290990Y1641064D01*
X290680Y1640795D01*
X290215Y1640642D01*
X289698Y1640604D01*
X289026Y1640680D01*
X288665Y1640795D01*
X288303Y1640987D01*
X288045Y1641255D01*
X287993Y1641524D01*
X288096Y1641792D01*
X288355Y1641984D01*
G01X290628Y1643589D02*
X290886Y1643819D01*
X291041Y1644087D01*
X291093Y1644432D01*
X290990Y1644777D01*
X290783Y1645045D01*
X290421Y1645237D01*
X290008Y1645275D01*
X289595Y1645199D01*
X289336Y1645007D01*
X289130Y1644739D01*
X289078Y1644470D01*
X289130Y1644202D01*
X289336Y1643857D01*
X287993Y1643972D01*
Y1645007D01*
G01X291021Y1653843D02*
Y1647643D01*
X287821D01*
Y1653843D01*
X291021D01*
G01X283483Y1639147D02*
X283328Y1638917D01*
X283225Y1638649D01*
Y1638342D01*
X283380Y1637997D01*
X283638Y1637729D01*
X283948Y1637537D01*
X284465Y1637384D01*
X284930Y1637346D01*
X285395Y1637422D01*
X285705Y1637537D01*
X286015Y1637767D01*
X286222Y1638036D01*
X286325Y1638304D01*
Y1638572D01*
X286222Y1638841D01*
X286067Y1639071D01*
X285860Y1639262D01*
G01X285033Y1640676D02*
X284672Y1640944D01*
X284465Y1641174D01*
X284362Y1641481D01*
X284465Y1641749D01*
X284672Y1641941D01*
X284982Y1642094D01*
X285343Y1642132D01*
X285653Y1642094D01*
X285963Y1641941D01*
X286222Y1641711D01*
X286325Y1641442D01*
X286222Y1641136D01*
X285912Y1640867D01*
X285447Y1640714D01*
X284930Y1640676D01*
X284258Y1640752D01*
X283897Y1640867D01*
X283535Y1641059D01*
X283277Y1641327D01*
X283225Y1641596D01*
X283328Y1641864D01*
X283587Y1642056D01*
G01X286325Y1644964D02*
X283225D01*
X285447Y1643546D01*
Y1645462D01*
G01X286386Y1657843D02*
Y1647643D01*
X281786D01*
Y1657843D01*
X286386D01*
G01X287921Y1650743D02*
X290921D01*
G01X286386Y1652743D02*
X281786D01*
G01X338582Y1693504D02*
G03I-31496J0D01*
G01X276985Y1717288D02*
Y1720388D01*
G01X278595D02*
Y1717288D01*
G01Y1718838D02*
X276985D01*
G01X280047Y1717908D02*
X280277Y1717546D01*
X280583Y1717340D01*
X280928Y1717288D01*
X281235Y1717340D01*
X281542Y1717598D01*
X281733Y1717908D01*
X281772Y1718218D01*
X281695Y1718580D01*
X281427Y1718838D01*
X281158Y1718941D01*
X280813D01*
G01X281158D02*
X281388Y1719096D01*
X281580Y1719355D01*
X281657Y1719665D01*
X281580Y1719975D01*
X281388Y1720233D01*
X281043Y1720388D01*
X280698Y1720336D01*
X280353Y1720130D01*
G01X288803Y1735711D02*
X288648Y1735481D01*
X288545Y1735213D01*
Y1734906D01*
X288700Y1734561D01*
X288958Y1734293D01*
X289268Y1734101D01*
X289785Y1733948D01*
X290250Y1733910D01*
X290715Y1733986D01*
X291025Y1734101D01*
X291335Y1734331D01*
X291542Y1734600D01*
X291645Y1734868D01*
Y1735136D01*
X291542Y1735405D01*
X291387Y1735635D01*
X291180Y1735826D01*
G01X291645Y1737891D02*
X290973Y1737968D01*
X290405Y1738083D01*
X289888Y1738236D01*
X289320Y1738428D01*
X288545Y1738735D01*
Y1737201D01*
G01X291645Y1741528D02*
X288545D01*
X290767Y1740110D01*
Y1742026D01*
G01X290999Y1728490D02*
X287999D01*
G01X287899Y1725390D02*
Y1731590D01*
X291099D01*
Y1725390D01*
X287899D01*
G01X283657Y1735711D02*
X283502Y1735481D01*
X283399Y1735213D01*
Y1734906D01*
X283554Y1734561D01*
X283812Y1734293D01*
X284122Y1734101D01*
X284639Y1733948D01*
X285104Y1733910D01*
X285569Y1733986D01*
X285879Y1734101D01*
X286189Y1734331D01*
X286396Y1734600D01*
X286499Y1734868D01*
Y1735136D01*
X286396Y1735405D01*
X286241Y1735635D01*
X286034Y1735826D01*
G01X286499Y1737891D02*
X285827Y1737968D01*
X285259Y1738083D01*
X284742Y1738236D01*
X284174Y1738428D01*
X283399Y1738735D01*
Y1737201D01*
G01X286034Y1740225D02*
X286292Y1740455D01*
X286447Y1740723D01*
X286499Y1741068D01*
X286396Y1741413D01*
X286189Y1741681D01*
X285827Y1741873D01*
X285414Y1741911D01*
X285001Y1741835D01*
X284742Y1741643D01*
X284536Y1741375D01*
X284484Y1741106D01*
X284536Y1740838D01*
X284742Y1740493D01*
X283399Y1740608D01*
Y1741643D01*
G01X286083Y1728490D02*
X283083D01*
G01X282983Y1725390D02*
Y1731590D01*
X286183D01*
Y1725390D01*
X282983D01*
G01X273511Y1735926D02*
X273356Y1735696D01*
X273253Y1735428D01*
Y1735121D01*
X273408Y1734776D01*
X273666Y1734508D01*
X273976Y1734316D01*
X274493Y1734163D01*
X274958Y1734125D01*
X275423Y1734201D01*
X275733Y1734316D01*
X276043Y1734546D01*
X276250Y1734815D01*
X276353Y1735083D01*
Y1735351D01*
X276250Y1735620D01*
X276095Y1735850D01*
X275888Y1736041D01*
G01X276353Y1738106D02*
X275681Y1738183D01*
X275113Y1738298D01*
X274596Y1738451D01*
X274028Y1738643D01*
X273253Y1738950D01*
Y1737416D01*
G01X276353Y1741206D02*
X275681Y1741283D01*
X275113Y1741398D01*
X274596Y1741551D01*
X274028Y1741743D01*
X273253Y1742050D01*
Y1740516D01*
G01X276204Y1728490D02*
X273204D01*
G01X273104Y1725390D02*
Y1731590D01*
X276304D01*
Y1725390D01*
X273104D01*
G01X278784Y1735782D02*
X278629Y1735552D01*
X278526Y1735284D01*
Y1734977D01*
X278681Y1734632D01*
X278939Y1734364D01*
X279249Y1734172D01*
X279766Y1734019D01*
X280231Y1733981D01*
X280696Y1734057D01*
X281006Y1734172D01*
X281316Y1734402D01*
X281523Y1734671D01*
X281626Y1734939D01*
Y1735207D01*
X281523Y1735476D01*
X281368Y1735706D01*
X281161Y1735897D01*
G01X281626Y1737962D02*
X280954Y1738039D01*
X280386Y1738154D01*
X279869Y1738307D01*
X279301Y1738499D01*
X278526Y1738806D01*
Y1737272D01*
G01X280334Y1740411D02*
X279973Y1740679D01*
X279766Y1740909D01*
X279663Y1741216D01*
X279766Y1741484D01*
X279973Y1741676D01*
X280283Y1741829D01*
X280644Y1741867D01*
X280954Y1741829D01*
X281264Y1741676D01*
X281523Y1741446D01*
X281626Y1741177D01*
X281523Y1740871D01*
X281213Y1740602D01*
X280748Y1740449D01*
X280231Y1740411D01*
X279559Y1740487D01*
X279198Y1740602D01*
X278836Y1740794D01*
X278578Y1741062D01*
X278526Y1741331D01*
X278629Y1741599D01*
X278888Y1741791D01*
G01X281203Y1728490D02*
X278203D01*
G01X278103Y1725390D02*
Y1731590D01*
X281303D01*
Y1725390D01*
X278103D01*
G01X282425Y1838148D02*
X282270Y1837918D01*
X282167Y1837650D01*
Y1837343D01*
X282322Y1836998D01*
X282580Y1836730D01*
X282890Y1836538D01*
X283407Y1836385D01*
X283872Y1836347D01*
X284337Y1836423D01*
X284647Y1836538D01*
X284957Y1836768D01*
X285164Y1837037D01*
X285267Y1837305D01*
Y1837573D01*
X285164Y1837842D01*
X285009Y1838072D01*
X284802Y1838263D01*
G01X285267Y1840328D02*
X284595Y1840405D01*
X284027Y1840520D01*
X283510Y1840673D01*
X282942Y1840865D01*
X282167Y1841172D01*
Y1839638D01*
G01X282684Y1842777D02*
X282374Y1843007D01*
X282219Y1843275D01*
X282167Y1843582D01*
X282270Y1843965D01*
X282529Y1844233D01*
X282839Y1844310D01*
X283149Y1844272D01*
X283407Y1844118D01*
X283924Y1843352D01*
X284285Y1843007D01*
X284802Y1842777D01*
X285267Y1842700D01*
Y1844310D01*
G01X285123Y1824971D02*
X288123D01*
G01X288223Y1828071D02*
Y1821871D01*
X285023D01*
Y1828071D01*
X288223D01*
G01X287619Y1838148D02*
X287464Y1837918D01*
X287361Y1837650D01*
Y1837343D01*
X287516Y1836998D01*
X287774Y1836730D01*
X288084Y1836538D01*
X288601Y1836385D01*
X289066Y1836347D01*
X289531Y1836423D01*
X289841Y1836538D01*
X290151Y1836768D01*
X290358Y1837037D01*
X290461Y1837305D01*
Y1837573D01*
X290358Y1837842D01*
X290203Y1838072D01*
X289996Y1838263D01*
G01X290461Y1840328D02*
X289789Y1840405D01*
X289221Y1840520D01*
X288704Y1840673D01*
X288136Y1840865D01*
X287361Y1841172D01*
Y1839638D01*
G01X289841Y1842662D02*
X290203Y1842892D01*
X290409Y1843198D01*
X290461Y1843543D01*
X290409Y1843850D01*
X290151Y1844157D01*
X289841Y1844348D01*
X289531Y1844387D01*
X289169Y1844310D01*
X288911Y1844042D01*
X288808Y1843773D01*
Y1843428D01*
G01Y1843773D02*
X288653Y1844003D01*
X288394Y1844195D01*
X288084Y1844272D01*
X287774Y1844195D01*
X287516Y1844003D01*
X287361Y1843658D01*
X287413Y1843313D01*
X287619Y1842968D01*
G01X290050Y1824971D02*
X293050D01*
G01X293150Y1828071D02*
Y1821871D01*
X289950D01*
Y1828071D01*
X293150D01*
G01X277458Y1838148D02*
X277303Y1837918D01*
X277200Y1837650D01*
Y1837343D01*
X277355Y1836998D01*
X277613Y1836730D01*
X277923Y1836538D01*
X278440Y1836385D01*
X278905Y1836347D01*
X279370Y1836423D01*
X279680Y1836538D01*
X279990Y1836768D01*
X280197Y1837037D01*
X280300Y1837305D01*
Y1837573D01*
X280197Y1837842D01*
X280042Y1838072D01*
X279835Y1838263D01*
G01X280300Y1840328D02*
X279628Y1840405D01*
X279060Y1840520D01*
X278543Y1840673D01*
X277975Y1840865D01*
X277200Y1841172D01*
Y1839638D01*
G01X280300Y1843505D02*
X277200D01*
X277820Y1843045D01*
G01X280300D02*
Y1843965D01*
G01X283366Y1832071D02*
Y1821871D01*
X278766D01*
Y1832071D01*
X283366D01*
G01Y1826971D02*
X278766D01*
G01X283976Y1867292D02*
Y1870392D01*
X284935D01*
X285241Y1870237D01*
X285433Y1870030D01*
X285510Y1869617D01*
X285433Y1869204D01*
X285203Y1868945D01*
X284935Y1868790D01*
X283976D01*
G01X284935D02*
X285510Y1867292D01*
G01X287843D02*
Y1870392D01*
X287383Y1869772D01*
G01Y1867292D02*
X288303D01*
G01X290100Y1867912D02*
X290330Y1867550D01*
X290636Y1867344D01*
X290981Y1867292D01*
X291288Y1867344D01*
X291595Y1867602D01*
X291786Y1867912D01*
X291825Y1868222D01*
X291748Y1868584D01*
X291480Y1868842D01*
X291211Y1868945D01*
X290866D01*
G01X291211D02*
X291441Y1869100D01*
X291633Y1869359D01*
X291710Y1869669D01*
X291633Y1869979D01*
X291441Y1870237D01*
X291096Y1870392D01*
X290751Y1870340D01*
X290406Y1870134D01*
G01X294043Y1867292D02*
Y1870392D01*
X293583Y1869772D01*
G01Y1867292D02*
X294503D01*
G01X290237Y1862965D02*
X284037D01*
Y1866165D01*
X290237D01*
Y1862965D01*
G01X283187Y1852797D02*
Y1855897D01*
X284146D01*
X284452Y1855742D01*
X284644Y1855535D01*
X284721Y1855122D01*
X284644Y1854709D01*
X284414Y1854450D01*
X284146Y1854295D01*
X283187D01*
G01X284146D02*
X284721Y1852797D01*
G01X287054D02*
Y1855897D01*
X286594Y1855277D01*
G01Y1852797D02*
X287514D01*
G01X289311Y1853417D02*
X289541Y1853055D01*
X289847Y1852849D01*
X290192Y1852797D01*
X290499Y1852849D01*
X290806Y1853107D01*
X290997Y1853417D01*
X291036Y1853727D01*
X290959Y1854089D01*
X290691Y1854347D01*
X290422Y1854450D01*
X290077D01*
G01X290422D02*
X290652Y1854605D01*
X290844Y1854864D01*
X290921Y1855174D01*
X290844Y1855484D01*
X290652Y1855742D01*
X290307Y1855897D01*
X289962Y1855845D01*
X289617Y1855639D01*
G01X292526Y1855380D02*
X292756Y1855690D01*
X293024Y1855845D01*
X293331Y1855897D01*
X293714Y1855794D01*
X293982Y1855535D01*
X294059Y1855225D01*
X294021Y1854915D01*
X293867Y1854657D01*
X293101Y1854140D01*
X292756Y1853779D01*
X292526Y1853262D01*
X292449Y1852797D01*
X294059D01*
G01X290319Y1857068D02*
X284119D01*
Y1860268D01*
X290319D01*
Y1857068D01*
G01X286946Y1888859D02*
X286791Y1888629D01*
X286688Y1888361D01*
Y1888054D01*
X286843Y1887709D01*
X287101Y1887441D01*
X287411Y1887249D01*
X287928Y1887096D01*
X288393Y1887058D01*
X288858Y1887134D01*
X289168Y1887249D01*
X289478Y1887479D01*
X289685Y1887748D01*
X289788Y1888016D01*
Y1888284D01*
X289685Y1888553D01*
X289530Y1888783D01*
X289323Y1888974D01*
G01X289788Y1891116D02*
X289736Y1891384D01*
X289581Y1891691D01*
X289323Y1891883D01*
X288961Y1891959D01*
X288600Y1891883D01*
X288290Y1891653D01*
X288135Y1891308D01*
Y1890924D01*
X288031Y1890694D01*
X287773Y1890503D01*
X287411Y1890426D01*
X287050Y1890541D01*
X286791Y1890809D01*
X286688Y1891116D01*
X286791Y1891423D01*
X287050Y1891691D01*
X287411Y1891806D01*
X287773Y1891729D01*
X288031Y1891538D01*
X288135Y1891308D01*
Y1890924D01*
X288290Y1890579D01*
X288600Y1890349D01*
X288961Y1890273D01*
X289323Y1890349D01*
X289581Y1890541D01*
X289736Y1890848D01*
X289788Y1891116D01*
G01Y1894216D02*
X286688D01*
X287308Y1893756D01*
G01X289788D02*
Y1894676D01*
G01X282156Y1889074D02*
X282001Y1888844D01*
X281898Y1888576D01*
Y1888269D01*
X282053Y1887924D01*
X282311Y1887656D01*
X282621Y1887464D01*
X283138Y1887311D01*
X283603Y1887273D01*
X284068Y1887349D01*
X284378Y1887464D01*
X284688Y1887694D01*
X284895Y1887963D01*
X284998Y1888231D01*
Y1888499D01*
X284895Y1888768D01*
X284740Y1888998D01*
X284533Y1889189D01*
G01X284998Y1891331D02*
X284946Y1891599D01*
X284791Y1891906D01*
X284533Y1892098D01*
X284171Y1892174D01*
X283810Y1892098D01*
X283500Y1891868D01*
X283345Y1891523D01*
Y1891139D01*
X283241Y1890909D01*
X282983Y1890718D01*
X282621Y1890641D01*
X282260Y1890756D01*
X282001Y1891024D01*
X281898Y1891331D01*
X282001Y1891638D01*
X282260Y1891906D01*
X282621Y1892021D01*
X282983Y1891944D01*
X283241Y1891753D01*
X283345Y1891523D01*
Y1891139D01*
X283500Y1890794D01*
X283810Y1890564D01*
X284171Y1890488D01*
X284533Y1890564D01*
X284791Y1890756D01*
X284946Y1891063D01*
X284998Y1891331D01*
G01X282415Y1893703D02*
X282105Y1893933D01*
X281950Y1894201D01*
X281898Y1894508D01*
X282001Y1894891D01*
X282260Y1895159D01*
X282570Y1895236D01*
X282880Y1895198D01*
X283138Y1895044D01*
X283655Y1894278D01*
X284016Y1893933D01*
X284533Y1893703D01*
X284998Y1893626D01*
Y1895236D01*
G01X277091Y1889288D02*
X276936Y1889058D01*
X276833Y1888790D01*
Y1888483D01*
X276988Y1888138D01*
X277246Y1887870D01*
X277556Y1887678D01*
X278073Y1887525D01*
X278538Y1887487D01*
X279003Y1887563D01*
X279313Y1887678D01*
X279623Y1887908D01*
X279830Y1888177D01*
X279933Y1888445D01*
Y1888713D01*
X279830Y1888982D01*
X279675Y1889212D01*
X279468Y1889403D01*
G01X279933Y1891545D02*
X279881Y1891813D01*
X279726Y1892120D01*
X279468Y1892312D01*
X279106Y1892388D01*
X278745Y1892312D01*
X278435Y1892082D01*
X278280Y1891737D01*
Y1891353D01*
X278176Y1891123D01*
X277918Y1890932D01*
X277556Y1890855D01*
X277195Y1890970D01*
X276936Y1891238D01*
X276833Y1891545D01*
X276936Y1891852D01*
X277195Y1892120D01*
X277556Y1892235D01*
X277918Y1892158D01*
X278176Y1891967D01*
X278280Y1891737D01*
Y1891353D01*
X278435Y1891008D01*
X278745Y1890778D01*
X279106Y1890702D01*
X279468Y1890778D01*
X279726Y1890970D01*
X279881Y1891277D01*
X279933Y1891545D01*
G01X279313Y1893802D02*
X279675Y1894032D01*
X279881Y1894338D01*
X279933Y1894683D01*
X279881Y1894990D01*
X279623Y1895297D01*
X279313Y1895488D01*
X279003Y1895527D01*
X278641Y1895450D01*
X278383Y1895182D01*
X278280Y1894913D01*
Y1894568D01*
G01Y1894913D02*
X278125Y1895143D01*
X277866Y1895335D01*
X277556Y1895412D01*
X277246Y1895335D01*
X276988Y1895143D01*
X276833Y1894798D01*
X276885Y1894453D01*
X277091Y1894108D01*
G01X271795Y1889360D02*
X271640Y1889130D01*
X271537Y1888862D01*
Y1888555D01*
X271692Y1888210D01*
X271950Y1887942D01*
X272260Y1887750D01*
X272777Y1887597D01*
X273242Y1887559D01*
X273707Y1887635D01*
X274017Y1887750D01*
X274327Y1887980D01*
X274534Y1888249D01*
X274637Y1888517D01*
Y1888785D01*
X274534Y1889054D01*
X274379Y1889284D01*
X274172Y1889475D01*
G01X274637Y1891617D02*
X274585Y1891885D01*
X274430Y1892192D01*
X274172Y1892384D01*
X273810Y1892460D01*
X273449Y1892384D01*
X273139Y1892154D01*
X272984Y1891809D01*
Y1891425D01*
X272880Y1891195D01*
X272622Y1891004D01*
X272260Y1890927D01*
X271899Y1891042D01*
X271640Y1891310D01*
X271537Y1891617D01*
X271640Y1891924D01*
X271899Y1892192D01*
X272260Y1892307D01*
X272622Y1892230D01*
X272880Y1892039D01*
X272984Y1891809D01*
Y1891425D01*
X273139Y1891080D01*
X273449Y1890850D01*
X273810Y1890774D01*
X274172Y1890850D01*
X274430Y1891042D01*
X274585Y1891349D01*
X274637Y1891617D01*
G01Y1895177D02*
X271537D01*
X273759Y1893759D01*
Y1895675D01*
G01X288621Y1903470D02*
X285621D01*
G01X285521Y1900370D02*
Y1906570D01*
X288721D01*
Y1900370D01*
X285521D01*
G01X284217Y1903470D02*
X281217D01*
G01X281117Y1900370D02*
Y1906570D01*
X284317D01*
Y1900370D01*
X281117D01*
G01X279762Y1903470D02*
X276762D01*
G01X276662Y1900370D02*
Y1906570D01*
X279862D01*
Y1900370D01*
X276662D01*
G01X275317Y1903470D02*
X272317D01*
G01X272217Y1900370D02*
Y1906570D01*
X275417D01*
Y1900370D01*
X272217D01*
G01X338583Y2043503D02*
G03I-31496J0D01*
G01X284311Y2071510D02*
Y2074610D01*
G01X285921D02*
Y2071510D01*
G01Y2073060D02*
X284311D01*
G01X288216Y2071510D02*
Y2074610D01*
X287756Y2073990D01*
G01Y2071510D02*
X288676D01*
G01X302651Y73818D02*
X305651D01*
G01X305751Y76918D02*
Y70718D01*
X302551D01*
Y76918D01*
X305751D01*
G01X307151Y73818D02*
X310151D01*
G01X310251Y76918D02*
Y70718D01*
X307051D01*
Y76918D01*
X310251D01*
G01X311589Y73818D02*
X314589D01*
G01X314689Y76918D02*
Y70718D01*
X311489D01*
Y76918D01*
X314689D01*
G01X298187Y73818D02*
X301187D01*
G01X301287Y76918D02*
Y70718D01*
X298087D01*
Y76918D01*
X301287D01*
G01X296783Y80918D02*
Y70718D01*
X292183D01*
Y80918D01*
X296783D01*
G01Y75818D02*
X292183D01*
G01X302314Y82706D02*
X302159Y82476D01*
X302056Y82208D01*
Y81901D01*
X302211Y81556D01*
X302469Y81288D01*
X302779Y81096D01*
X303296Y80943D01*
X303761Y80905D01*
X304226Y80981D01*
X304536Y81096D01*
X304846Y81326D01*
X305053Y81595D01*
X305156Y81863D01*
Y82131D01*
X305053Y82400D01*
X304898Y82630D01*
X304691Y82821D01*
G01X304536Y84120D02*
X304898Y84350D01*
X305104Y84656D01*
X305156Y85001D01*
X305104Y85308D01*
X304846Y85615D01*
X304536Y85806D01*
X304226Y85845D01*
X303864Y85768D01*
X303606Y85500D01*
X303503Y85231D01*
Y84886D01*
G01Y85231D02*
X303348Y85461D01*
X303089Y85653D01*
X302779Y85730D01*
X302469Y85653D01*
X302211Y85461D01*
X302056Y85116D01*
X302108Y84771D01*
X302314Y84426D01*
G01X307066Y82706D02*
X306911Y82476D01*
X306808Y82208D01*
Y81901D01*
X306963Y81556D01*
X307221Y81288D01*
X307531Y81096D01*
X308048Y80943D01*
X308513Y80905D01*
X308978Y80981D01*
X309288Y81096D01*
X309598Y81326D01*
X309805Y81595D01*
X309908Y81863D01*
Y82131D01*
X309805Y82400D01*
X309650Y82630D01*
X309443Y82821D01*
G01X309908Y85423D02*
X306808D01*
X309030Y84005D01*
Y85921D01*
G01X311542Y82706D02*
X311387Y82476D01*
X311284Y82208D01*
Y81901D01*
X311439Y81556D01*
X311697Y81288D01*
X312007Y81096D01*
X312524Y80943D01*
X312989Y80905D01*
X313454Y80981D01*
X313764Y81096D01*
X314074Y81326D01*
X314281Y81595D01*
X314384Y81863D01*
Y82131D01*
X314281Y82400D01*
X314126Y82630D01*
X313919Y82821D01*
G01Y84120D02*
X314177Y84350D01*
X314332Y84618D01*
X314384Y84963D01*
X314281Y85308D01*
X314074Y85576D01*
X313712Y85768D01*
X313299Y85806D01*
X312886Y85730D01*
X312627Y85538D01*
X312421Y85270D01*
X312369Y85001D01*
X312421Y84733D01*
X312627Y84388D01*
X311284Y84503D01*
Y85538D01*
G01X298064Y82706D02*
X297909Y82476D01*
X297806Y82208D01*
Y81901D01*
X297961Y81556D01*
X298219Y81288D01*
X298529Y81096D01*
X299046Y80943D01*
X299511Y80905D01*
X299976Y80981D01*
X300286Y81096D01*
X300596Y81326D01*
X300803Y81595D01*
X300906Y81863D01*
Y82131D01*
X300803Y82400D01*
X300648Y82630D01*
X300441Y82821D01*
G01X298323Y84235D02*
X298013Y84465D01*
X297858Y84733D01*
X297806Y85040D01*
X297909Y85423D01*
X298168Y85691D01*
X298478Y85768D01*
X298788Y85730D01*
X299046Y85576D01*
X299563Y84810D01*
X299924Y84465D01*
X300441Y84235D01*
X300906Y84158D01*
Y85768D01*
G01X293329Y85967D02*
X293174Y85737D01*
X293071Y85469D01*
Y85162D01*
X293226Y84817D01*
X293484Y84549D01*
X293794Y84357D01*
X294311Y84204D01*
X294776Y84166D01*
X295241Y84242D01*
X295551Y84357D01*
X295861Y84587D01*
X296068Y84856D01*
X296171Y85124D01*
Y85392D01*
X296068Y85661D01*
X295913Y85891D01*
X295706Y86082D01*
G01X296171Y88224D02*
X293071D01*
X293691Y87764D01*
G01X296171D02*
Y88684D01*
G01X320536Y308267D02*
G03I-13450J0D01*
G01X293814Y334067D02*
X293659Y333837D01*
X293556Y333569D01*
Y333262D01*
X293711Y332917D01*
X293969Y332649D01*
X294279Y332457D01*
X294796Y332304D01*
X295261Y332266D01*
X295726Y332342D01*
X296036Y332457D01*
X296346Y332687D01*
X296553Y332956D01*
X296656Y333224D01*
Y333492D01*
X296553Y333761D01*
X296398Y333991D01*
X296191Y334182D01*
G01X296656Y336324D02*
X293556D01*
X294176Y335864D01*
G01X296656D02*
Y336784D01*
G01Y339424D02*
X296604Y339692D01*
X296449Y339999D01*
X296191Y340191D01*
X295829Y340267D01*
X295468Y340191D01*
X295158Y339961D01*
X295003Y339616D01*
Y339232D01*
X294899Y339002D01*
X294641Y338811D01*
X294279Y338734D01*
X293918Y338849D01*
X293659Y339117D01*
X293556Y339424D01*
X293659Y339731D01*
X293918Y339999D01*
X294279Y340114D01*
X294641Y340037D01*
X294899Y339846D01*
X295003Y339616D01*
Y339232D01*
X295158Y338887D01*
X295468Y338657D01*
X295829Y338581D01*
X296191Y338657D01*
X296449Y338849D01*
X296604Y339156D01*
X296656Y339424D01*
G01X296006Y328092D02*
X293006D01*
G01X292906Y324992D02*
Y331192D01*
X296106D01*
Y324992D01*
X292906D01*
G01X300483Y325207D02*
Y328307D01*
G01X302093D02*
Y325207D01*
G01Y326757D02*
X300483D01*
G01X304388Y325207D02*
Y328307D01*
X303928Y327687D01*
G01Y325207D02*
X304848D01*
G01X307948D02*
Y328307D01*
X306530Y326085D01*
X308446D01*
G01X294009Y602062D02*
X297009D01*
G01X297109Y605162D02*
Y598962D01*
X293909D01*
Y605162D01*
X297109D01*
G01X293907Y614443D02*
X293752Y614213D01*
X293649Y613945D01*
Y613638D01*
X293804Y613293D01*
X294062Y613025D01*
X294372Y612833D01*
X294889Y612680D01*
X295354Y612642D01*
X295819Y612718D01*
X296129Y612833D01*
X296439Y613063D01*
X296646Y613332D01*
X296749Y613600D01*
Y613868D01*
X296646Y614137D01*
X296491Y614367D01*
X296284Y614558D01*
G01X294166Y615972D02*
X293856Y616202D01*
X293701Y616470D01*
X293649Y616777D01*
X293752Y617160D01*
X294011Y617428D01*
X294321Y617505D01*
X294631Y617467D01*
X294889Y617313D01*
X295406Y616547D01*
X295767Y616202D01*
X296284Y615972D01*
X296749Y615895D01*
Y617505D01*
G01Y620260D02*
X293649D01*
X295871Y618842D01*
Y620758D01*
G01X298072Y860121D02*
Y863221D01*
G01X299682D02*
Y860121D01*
G01Y861671D02*
X298072D01*
G01X301900Y860121D02*
X301977Y860793D01*
X302092Y861361D01*
X302245Y861878D01*
X302437Y862446D01*
X302744Y863221D01*
X301210D01*
G01X304495Y949964D02*
X304340Y949734D01*
X304237Y949466D01*
Y949159D01*
X304392Y948814D01*
X304650Y948546D01*
X304960Y948354D01*
X305477Y948201D01*
X305942Y948163D01*
X306407Y948239D01*
X306717Y948354D01*
X307027Y948584D01*
X307234Y948853D01*
X307337Y949121D01*
Y949389D01*
X307234Y949658D01*
X307079Y949888D01*
X306872Y950079D01*
G01X306717Y951378D02*
X307079Y951608D01*
X307285Y951914D01*
X307337Y952259D01*
X307285Y952566D01*
X307027Y952873D01*
X306717Y953064D01*
X306407Y953103D01*
X306045Y953026D01*
X305787Y952758D01*
X305684Y952489D01*
Y952144D01*
G01Y952489D02*
X305529Y952719D01*
X305270Y952911D01*
X304960Y952988D01*
X304650Y952911D01*
X304392Y952719D01*
X304237Y952374D01*
X304289Y952029D01*
X304495Y951684D01*
G01X307337Y955244D02*
X306665Y955321D01*
X306097Y955436D01*
X305580Y955589D01*
X305012Y955781D01*
X304237Y956088D01*
Y954554D01*
G01X309602Y949964D02*
X309447Y949734D01*
X309344Y949466D01*
Y949159D01*
X309499Y948814D01*
X309757Y948546D01*
X310067Y948354D01*
X310584Y948201D01*
X311049Y948163D01*
X311514Y948239D01*
X311824Y948354D01*
X312134Y948584D01*
X312341Y948853D01*
X312444Y949121D01*
Y949389D01*
X312341Y949658D01*
X312186Y949888D01*
X311979Y950079D01*
G01X311824Y951378D02*
X312186Y951608D01*
X312392Y951914D01*
X312444Y952259D01*
X312392Y952566D01*
X312134Y952873D01*
X311824Y953064D01*
X311514Y953103D01*
X311152Y953026D01*
X310894Y952758D01*
X310791Y952489D01*
Y952144D01*
G01Y952489D02*
X310636Y952719D01*
X310377Y952911D01*
X310067Y952988D01*
X309757Y952911D01*
X309499Y952719D01*
X309344Y952374D01*
X309396Y952029D01*
X309602Y951684D01*
G01X312444Y955321D02*
X312392Y955589D01*
X312237Y955896D01*
X311979Y956088D01*
X311617Y956164D01*
X311256Y956088D01*
X310946Y955858D01*
X310791Y955513D01*
Y955129D01*
X310687Y954899D01*
X310429Y954708D01*
X310067Y954631D01*
X309706Y954746D01*
X309447Y955014D01*
X309344Y955321D01*
X309447Y955628D01*
X309706Y955896D01*
X310067Y956011D01*
X310429Y955934D01*
X310687Y955743D01*
X310791Y955513D01*
Y955129D01*
X310946Y954784D01*
X311256Y954554D01*
X311617Y954478D01*
X311979Y954554D01*
X312237Y954746D01*
X312392Y955053D01*
X312444Y955321D01*
G01X297474Y953961D02*
Y947761D01*
X294274D01*
Y953961D01*
X297474D01*
G01X299394Y949964D02*
X299239Y949734D01*
X299136Y949466D01*
Y949159D01*
X299291Y948814D01*
X299549Y948546D01*
X299859Y948354D01*
X300376Y948201D01*
X300841Y948163D01*
X301306Y948239D01*
X301616Y948354D01*
X301926Y948584D01*
X302133Y948853D01*
X302236Y949121D01*
Y949389D01*
X302133Y949658D01*
X301978Y949888D01*
X301771Y950079D01*
G01X301616Y951378D02*
X301978Y951608D01*
X302184Y951914D01*
X302236Y952259D01*
X302184Y952566D01*
X301926Y952873D01*
X301616Y953064D01*
X301306Y953103D01*
X300944Y953026D01*
X300686Y952758D01*
X300583Y952489D01*
Y952144D01*
G01Y952489D02*
X300428Y952719D01*
X300169Y952911D01*
X299859Y952988D01*
X299549Y952911D01*
X299291Y952719D01*
X299136Y952374D01*
X299188Y952029D01*
X299394Y951684D01*
G01X300944Y954593D02*
X300583Y954861D01*
X300376Y955091D01*
X300273Y955398D01*
X300376Y955666D01*
X300583Y955858D01*
X300893Y956011D01*
X301254Y956049D01*
X301564Y956011D01*
X301874Y955858D01*
X302133Y955628D01*
X302236Y955359D01*
X302133Y955053D01*
X301823Y954784D01*
X301358Y954631D01*
X300841Y954593D01*
X300169Y954669D01*
X299808Y954784D01*
X299446Y954976D01*
X299188Y955244D01*
X299136Y955513D01*
X299239Y955781D01*
X299498Y955973D01*
G01X313990Y930971D02*
Y934071D01*
X314910D01*
X315217Y933916D01*
X315447Y933554D01*
X315524Y933141D01*
X315447Y932728D01*
X315255Y932418D01*
X314910Y932263D01*
X313990D01*
G01X317857Y930971D02*
Y934071D01*
X317397Y933451D01*
G01Y930971D02*
X318317D01*
G01X320229Y932263D02*
X320497Y932624D01*
X320727Y932831D01*
X321034Y932934D01*
X321302Y932831D01*
X321494Y932624D01*
X321647Y932314D01*
X321685Y931953D01*
X321647Y931643D01*
X321494Y931333D01*
X321264Y931074D01*
X320995Y930971D01*
X320689Y931074D01*
X320420Y931384D01*
X320267Y931849D01*
X320229Y932366D01*
X320305Y933038D01*
X320420Y933399D01*
X320612Y933761D01*
X320880Y934019D01*
X321149Y934071D01*
X321417Y933968D01*
X321609Y933709D01*
G01X294374Y950861D02*
X297374D01*
G01X294112Y1006086D02*
X293957Y1005856D01*
X293854Y1005588D01*
Y1005281D01*
X294009Y1004936D01*
X294267Y1004668D01*
X294577Y1004476D01*
X295094Y1004323D01*
X295559Y1004285D01*
X296024Y1004361D01*
X296334Y1004476D01*
X296644Y1004706D01*
X296851Y1004975D01*
X296954Y1005243D01*
Y1005511D01*
X296851Y1005780D01*
X296696Y1006010D01*
X296489Y1006201D01*
G01X296954Y1008803D02*
X293854D01*
X296076Y1007385D01*
Y1009301D01*
G01X295662Y1010715D02*
X295301Y1010983D01*
X295094Y1011213D01*
X294991Y1011520D01*
X295094Y1011788D01*
X295301Y1011980D01*
X295611Y1012133D01*
X295972Y1012171D01*
X296282Y1012133D01*
X296592Y1011980D01*
X296851Y1011750D01*
X296954Y1011481D01*
X296851Y1011175D01*
X296541Y1010906D01*
X296076Y1010753D01*
X295559Y1010715D01*
X294887Y1010791D01*
X294526Y1010906D01*
X294164Y1011098D01*
X293906Y1011366D01*
X293854Y1011635D01*
X293957Y1011903D01*
X294216Y1012095D01*
G01X296117Y1021457D02*
X293117D01*
G01X293017Y1018357D02*
Y1024557D01*
X296217D01*
Y1018357D01*
X293017D01*
G01X302849Y1124418D02*
X302694Y1124188D01*
X302591Y1123920D01*
Y1123613D01*
X302746Y1123268D01*
X303004Y1123000D01*
X303314Y1122808D01*
X303831Y1122655D01*
X304296Y1122617D01*
X304761Y1122693D01*
X305071Y1122808D01*
X305381Y1123038D01*
X305588Y1123307D01*
X305691Y1123575D01*
Y1123843D01*
X305588Y1124112D01*
X305433Y1124342D01*
X305226Y1124533D01*
G01X305691Y1127135D02*
X302591D01*
X304813Y1125717D01*
Y1127633D01*
G01X305691Y1130235D02*
X302591D01*
X304813Y1128817D01*
Y1130733D01*
G01X307522Y1124418D02*
X307367Y1124188D01*
X307264Y1123920D01*
Y1123613D01*
X307419Y1123268D01*
X307677Y1123000D01*
X307987Y1122808D01*
X308504Y1122655D01*
X308969Y1122617D01*
X309434Y1122693D01*
X309744Y1122808D01*
X310054Y1123038D01*
X310261Y1123307D01*
X310364Y1123575D01*
Y1123843D01*
X310261Y1124112D01*
X310106Y1124342D01*
X309899Y1124533D01*
G01X310364Y1127135D02*
X307264D01*
X309486Y1125717D01*
Y1127633D01*
G01X309899Y1128932D02*
X310157Y1129162D01*
X310312Y1129430D01*
X310364Y1129775D01*
X310261Y1130120D01*
X310054Y1130388D01*
X309692Y1130580D01*
X309279Y1130618D01*
X308866Y1130542D01*
X308607Y1130350D01*
X308401Y1130082D01*
X308349Y1129813D01*
X308401Y1129545D01*
X308607Y1129200D01*
X307264Y1129315D01*
Y1130350D01*
G01X291198Y1125851D02*
X294198D01*
G01X294298Y1128951D02*
Y1122751D01*
X291098D01*
Y1128951D01*
X294298D01*
G01X297339Y1124418D02*
X297184Y1124188D01*
X297081Y1123920D01*
Y1123613D01*
X297236Y1123268D01*
X297494Y1123000D01*
X297804Y1122808D01*
X298321Y1122655D01*
X298786Y1122617D01*
X299251Y1122693D01*
X299561Y1122808D01*
X299871Y1123038D01*
X300078Y1123307D01*
X300181Y1123575D01*
Y1123843D01*
X300078Y1124112D01*
X299923Y1124342D01*
X299716Y1124533D01*
G01X300181Y1127135D02*
X297081D01*
X299303Y1125717D01*
Y1127633D01*
G01X299561Y1128932D02*
X299923Y1129162D01*
X300129Y1129468D01*
X300181Y1129813D01*
X300129Y1130120D01*
X299871Y1130427D01*
X299561Y1130618D01*
X299251Y1130657D01*
X298889Y1130580D01*
X298631Y1130312D01*
X298528Y1130043D01*
Y1129698D01*
G01Y1130043D02*
X298373Y1130273D01*
X298114Y1130465D01*
X297804Y1130542D01*
X297494Y1130465D01*
X297236Y1130273D01*
X297081Y1129928D01*
X297133Y1129583D01*
X297339Y1129238D01*
G01X313884Y1155969D02*
Y1159069D01*
X314843D01*
X315149Y1158914D01*
X315341Y1158707D01*
X315418Y1158294D01*
X315341Y1157881D01*
X315111Y1157622D01*
X314843Y1157467D01*
X313884D01*
G01X314843D02*
X315418Y1155969D01*
G01X317751D02*
Y1159069D01*
X317291Y1158449D01*
G01Y1155969D02*
X318211D01*
G01X320123Y1158552D02*
X320353Y1158862D01*
X320621Y1159017D01*
X320928Y1159069D01*
X321311Y1158966D01*
X321579Y1158707D01*
X321656Y1158397D01*
X321618Y1158087D01*
X321464Y1157829D01*
X320698Y1157312D01*
X320353Y1156951D01*
X320123Y1156434D01*
X320046Y1155969D01*
X321656D01*
G01X324411D02*
Y1159069D01*
X322993Y1156847D01*
X324909D01*
G01X314786Y1176193D02*
Y1179293D01*
X315745D01*
X316051Y1179138D01*
X316243Y1178931D01*
X316320Y1178518D01*
X316243Y1178105D01*
X316013Y1177846D01*
X315745Y1177691D01*
X314786D01*
G01X315745D02*
X316320Y1176193D01*
G01X318653D02*
Y1179293D01*
X318193Y1178673D01*
G01Y1176193D02*
X319113D01*
G01X321025Y1178776D02*
X321255Y1179086D01*
X321523Y1179241D01*
X321830Y1179293D01*
X322213Y1179190D01*
X322481Y1178931D01*
X322558Y1178621D01*
X322520Y1178311D01*
X322366Y1178053D01*
X321600Y1177536D01*
X321255Y1177175D01*
X321025Y1176658D01*
X320948Y1176193D01*
X322558D01*
G01X324010Y1176813D02*
X324240Y1176451D01*
X324546Y1176245D01*
X324891Y1176193D01*
X325198Y1176245D01*
X325505Y1176503D01*
X325696Y1176813D01*
X325735Y1177123D01*
X325658Y1177485D01*
X325390Y1177743D01*
X325121Y1177846D01*
X324776D01*
G01X325121D02*
X325351Y1178001D01*
X325543Y1178260D01*
X325620Y1178570D01*
X325543Y1178880D01*
X325351Y1179138D01*
X325006Y1179293D01*
X324661Y1179241D01*
X324316Y1179035D01*
G01X292917Y1289431D02*
X292762Y1289201D01*
X292659Y1288933D01*
Y1288626D01*
X292814Y1288281D01*
X293072Y1288013D01*
X293382Y1287821D01*
X293899Y1287668D01*
X294364Y1287630D01*
X294829Y1287706D01*
X295139Y1287821D01*
X295449Y1288051D01*
X295656Y1288320D01*
X295759Y1288588D01*
Y1288856D01*
X295656Y1289125D01*
X295501Y1289355D01*
X295294Y1289546D01*
G01Y1290845D02*
X295552Y1291075D01*
X295707Y1291343D01*
X295759Y1291688D01*
X295656Y1292033D01*
X295449Y1292301D01*
X295087Y1292493D01*
X294674Y1292531D01*
X294261Y1292455D01*
X294002Y1292263D01*
X293796Y1291995D01*
X293744Y1291726D01*
X293796Y1291458D01*
X294002Y1291113D01*
X292659Y1291228D01*
Y1292263D01*
G01X293176Y1294060D02*
X292866Y1294290D01*
X292711Y1294558D01*
X292659Y1294865D01*
X292762Y1295248D01*
X293021Y1295516D01*
X293331Y1295593D01*
X293641Y1295555D01*
X293899Y1295401D01*
X294416Y1294635D01*
X294777Y1294290D01*
X295294Y1294060D01*
X295759Y1293983D01*
Y1295593D01*
G01X292633Y1300522D02*
X295633D01*
G01X295733Y1303622D02*
Y1297422D01*
X292533D01*
Y1303622D01*
X295733D01*
G01X304216Y1527637D02*
Y1530737D01*
X305175D01*
X305481Y1530582D01*
X305673Y1530375D01*
X305750Y1529962D01*
X305673Y1529549D01*
X305443Y1529290D01*
X305175Y1529135D01*
X304216D01*
G01X305175D02*
X305750Y1527637D01*
G01X308083D02*
Y1530737D01*
X307623Y1530117D01*
G01Y1527637D02*
X308543D01*
G01X310455Y1530220D02*
X310685Y1530530D01*
X310953Y1530685D01*
X311260Y1530737D01*
X311643Y1530634D01*
X311911Y1530375D01*
X311988Y1530065D01*
X311950Y1529755D01*
X311796Y1529497D01*
X311030Y1528980D01*
X310685Y1528619D01*
X310455Y1528102D01*
X310378Y1527637D01*
X311988D01*
G01X314206D02*
X314283Y1528309D01*
X314398Y1528877D01*
X314551Y1529394D01*
X314743Y1529962D01*
X315050Y1530737D01*
X313516D01*
G01X310431Y1522801D02*
X304231D01*
Y1526001D01*
X310431D01*
Y1522801D01*
G01X302996Y1507074D02*
Y1510174D01*
X303955D01*
X304261Y1510019D01*
X304453Y1509812D01*
X304530Y1509399D01*
X304453Y1508986D01*
X304223Y1508727D01*
X303955Y1508572D01*
X302996D01*
G01X303955D02*
X304530Y1507074D01*
G01X306863D02*
Y1510174D01*
X306403Y1509554D01*
G01Y1507074D02*
X307323D01*
G01X309235Y1509657D02*
X309465Y1509967D01*
X309733Y1510122D01*
X310040Y1510174D01*
X310423Y1510071D01*
X310691Y1509812D01*
X310768Y1509502D01*
X310730Y1509192D01*
X310576Y1508934D01*
X309810Y1508417D01*
X309465Y1508056D01*
X309235Y1507539D01*
X309158Y1507074D01*
X310768D01*
G01X313063D02*
X313331Y1507126D01*
X313638Y1507281D01*
X313830Y1507539D01*
X313906Y1507901D01*
X313830Y1508262D01*
X313600Y1508572D01*
X313255Y1508727D01*
X312871D01*
X312641Y1508831D01*
X312450Y1509089D01*
X312373Y1509451D01*
X312488Y1509812D01*
X312756Y1510071D01*
X313063Y1510174D01*
X313370Y1510071D01*
X313638Y1509812D01*
X313753Y1509451D01*
X313676Y1509089D01*
X313485Y1508831D01*
X313255Y1508727D01*
X312871D01*
X312526Y1508572D01*
X312296Y1508262D01*
X312220Y1507901D01*
X312296Y1507539D01*
X312488Y1507281D01*
X312795Y1507126D01*
X313063Y1507074D01*
G01X310161Y1512283D02*
X303961D01*
Y1515483D01*
X310161D01*
Y1512283D01*
G01X304801Y1555289D02*
X304646Y1555059D01*
X304543Y1554791D01*
Y1554484D01*
X304698Y1554139D01*
X304956Y1553871D01*
X305266Y1553679D01*
X305783Y1553526D01*
X306248Y1553488D01*
X306713Y1553564D01*
X307023Y1553679D01*
X307333Y1553909D01*
X307540Y1554178D01*
X307643Y1554446D01*
Y1554714D01*
X307540Y1554983D01*
X307385Y1555213D01*
X307178Y1555404D01*
G01X306351Y1556818D02*
X305990Y1557086D01*
X305783Y1557316D01*
X305680Y1557623D01*
X305783Y1557891D01*
X305990Y1558083D01*
X306300Y1558236D01*
X306661Y1558274D01*
X306971Y1558236D01*
X307281Y1558083D01*
X307540Y1557853D01*
X307643Y1557584D01*
X307540Y1557278D01*
X307230Y1557009D01*
X306765Y1556856D01*
X306248Y1556818D01*
X305576Y1556894D01*
X305215Y1557009D01*
X304853Y1557201D01*
X304595Y1557469D01*
X304543Y1557738D01*
X304646Y1558006D01*
X304905Y1558198D01*
G01X307643Y1560569D02*
X306971Y1560646D01*
X306403Y1560761D01*
X305886Y1560914D01*
X305318Y1561106D01*
X304543Y1561413D01*
Y1559879D01*
G01X306370Y1549026D02*
X303370D01*
G01X303270Y1545926D02*
Y1552126D01*
X306470D01*
Y1545926D01*
X303270D01*
G01X294561Y1555290D02*
X294406Y1555060D01*
X294303Y1554792D01*
Y1554485D01*
X294458Y1554140D01*
X294716Y1553872D01*
X295026Y1553680D01*
X295543Y1553527D01*
X296008Y1553489D01*
X296473Y1553565D01*
X296783Y1553680D01*
X297093Y1553910D01*
X297300Y1554179D01*
X297403Y1554447D01*
Y1554715D01*
X297300Y1554984D01*
X297145Y1555214D01*
X296938Y1555405D01*
G01X296111Y1556819D02*
X295750Y1557087D01*
X295543Y1557317D01*
X295440Y1557624D01*
X295543Y1557892D01*
X295750Y1558084D01*
X296060Y1558237D01*
X296421Y1558275D01*
X296731Y1558237D01*
X297041Y1558084D01*
X297300Y1557854D01*
X297403Y1557585D01*
X297300Y1557279D01*
X296990Y1557010D01*
X296525Y1556857D01*
X296008Y1556819D01*
X295336Y1556895D01*
X294975Y1557010D01*
X294613Y1557202D01*
X294355Y1557470D01*
X294303Y1557739D01*
X294406Y1558007D01*
X294665Y1558199D01*
G01X297041Y1559995D02*
X297300Y1560264D01*
X297403Y1560570D01*
X297300Y1560877D01*
X296990Y1561145D01*
X296525Y1561337D01*
X296060Y1561414D01*
X295491D01*
X295026Y1561337D01*
X294613Y1561145D01*
X294406Y1560915D01*
X294303Y1560647D01*
X294406Y1560340D01*
X294613Y1560110D01*
X294923Y1559957D01*
X295336Y1559880D01*
X295698Y1559957D01*
X296060Y1560149D01*
X296266Y1560379D01*
X296318Y1560647D01*
X296215Y1560954D01*
X295956Y1561184D01*
X295491Y1561414D01*
G01X297175Y1549026D02*
X294175D01*
G01X294075Y1545926D02*
Y1552126D01*
X297275D01*
Y1545926D01*
X294075D01*
G01X299704Y1555290D02*
X299549Y1555060D01*
X299446Y1554792D01*
Y1554485D01*
X299601Y1554140D01*
X299859Y1553872D01*
X300169Y1553680D01*
X300686Y1553527D01*
X301151Y1553489D01*
X301616Y1553565D01*
X301926Y1553680D01*
X302236Y1553910D01*
X302443Y1554179D01*
X302546Y1554447D01*
Y1554715D01*
X302443Y1554984D01*
X302288Y1555214D01*
X302081Y1555405D01*
G01X301254Y1556819D02*
X300893Y1557087D01*
X300686Y1557317D01*
X300583Y1557624D01*
X300686Y1557892D01*
X300893Y1558084D01*
X301203Y1558237D01*
X301564Y1558275D01*
X301874Y1558237D01*
X302184Y1558084D01*
X302443Y1557854D01*
X302546Y1557585D01*
X302443Y1557279D01*
X302133Y1557010D01*
X301668Y1556857D01*
X301151Y1556819D01*
X300479Y1556895D01*
X300118Y1557010D01*
X299756Y1557202D01*
X299498Y1557470D01*
X299446Y1557739D01*
X299549Y1558007D01*
X299808Y1558199D01*
G01X302546Y1560647D02*
X302494Y1560915D01*
X302339Y1561222D01*
X302081Y1561414D01*
X301719Y1561490D01*
X301358Y1561414D01*
X301048Y1561184D01*
X300893Y1560839D01*
Y1560455D01*
X300789Y1560225D01*
X300531Y1560034D01*
X300169Y1559957D01*
X299808Y1560072D01*
X299549Y1560340D01*
X299446Y1560647D01*
X299549Y1560954D01*
X299808Y1561222D01*
X300169Y1561337D01*
X300531Y1561260D01*
X300789Y1561069D01*
X300893Y1560839D01*
Y1560455D01*
X301048Y1560110D01*
X301358Y1559880D01*
X301719Y1559804D01*
X302081Y1559880D01*
X302339Y1560072D01*
X302494Y1560379D01*
X302546Y1560647D01*
G01X301892Y1549026D02*
X298892D01*
G01X298792Y1545926D02*
Y1552126D01*
X301992D01*
Y1545926D01*
X298792D01*
G01X292920Y1639075D02*
X292765Y1638845D01*
X292662Y1638577D01*
Y1638270D01*
X292817Y1637925D01*
X293075Y1637657D01*
X293385Y1637465D01*
X293902Y1637312D01*
X294367Y1637274D01*
X294832Y1637350D01*
X295142Y1637465D01*
X295452Y1637695D01*
X295659Y1637964D01*
X295762Y1638232D01*
Y1638500D01*
X295659Y1638769D01*
X295504Y1638999D01*
X295297Y1639190D01*
G01X294470Y1640604D02*
X294109Y1640872D01*
X293902Y1641102D01*
X293799Y1641409D01*
X293902Y1641677D01*
X294109Y1641869D01*
X294419Y1642022D01*
X294780Y1642060D01*
X295090Y1642022D01*
X295400Y1641869D01*
X295659Y1641639D01*
X295762Y1641370D01*
X295659Y1641064D01*
X295349Y1640795D01*
X294884Y1640642D01*
X294367Y1640604D01*
X293695Y1640680D01*
X293334Y1640795D01*
X292972Y1640987D01*
X292714Y1641255D01*
X292662Y1641524D01*
X292765Y1641792D01*
X293024Y1641984D01*
G01X294470Y1643704D02*
X294109Y1643972D01*
X293902Y1644202D01*
X293799Y1644509D01*
X293902Y1644777D01*
X294109Y1644969D01*
X294419Y1645122D01*
X294780Y1645160D01*
X295090Y1645122D01*
X295400Y1644969D01*
X295659Y1644739D01*
X295762Y1644470D01*
X295659Y1644164D01*
X295349Y1643895D01*
X294884Y1643742D01*
X294367Y1643704D01*
X293695Y1643780D01*
X293334Y1643895D01*
X292972Y1644087D01*
X292714Y1644355D01*
X292662Y1644624D01*
X292765Y1644892D01*
X293024Y1645084D01*
G01X295690Y1653843D02*
Y1647643D01*
X292490D01*
Y1653843D01*
X295690D01*
G01X292590Y1650743D02*
X295590D01*
G01X293636Y1883071D02*
Y1885021D01*
G02X307086Y1898471I13450J0D01*
G02X320536Y1885021I0J-13450D01*
G01Y1881121D01*
G02X307086Y1867671I-13450J0D01*
G02X293636Y1881121I0J13450D01*
G01Y1883071D01*
G01X294451Y1902340D02*
Y1905440D01*
G01X296061D02*
Y1902340D01*
G01Y1903890D02*
X294451D01*
G01X298356Y1902340D02*
Y1905440D01*
X297896Y1904820D01*
G01Y1902340D02*
X298816D01*
G01X300613Y1902960D02*
X300843Y1902598D01*
X301149Y1902392D01*
X301494Y1902340D01*
X301801Y1902392D01*
X302108Y1902650D01*
X302299Y1902960D01*
X302338Y1903270D01*
X302261Y1903632D01*
X301993Y1903890D01*
X301724Y1903993D01*
X301379D01*
G01X301724D02*
X301954Y1904148D01*
X302146Y1904407D01*
X302223Y1904717D01*
X302146Y1905027D01*
X301954Y1905285D01*
X301609Y1905440D01*
X301264Y1905388D01*
X300919Y1905182D01*
G01X313213Y1988360D02*
X313058Y1988130D01*
X312955Y1987862D01*
Y1987555D01*
X313110Y1987210D01*
X313368Y1986942D01*
X313678Y1986750D01*
X314195Y1986597D01*
X314660Y1986559D01*
X315125Y1986635D01*
X315435Y1986750D01*
X315745Y1986980D01*
X315952Y1987249D01*
X316055Y1987517D01*
Y1987785D01*
X315952Y1988054D01*
X315797Y1988284D01*
X315590Y1988475D01*
G01X316055Y1990540D02*
X315383Y1990617D01*
X314815Y1990732D01*
X314298Y1990885D01*
X313730Y1991077D01*
X312955Y1991384D01*
Y1989850D01*
G01X316055Y1993717D02*
X316003Y1993985D01*
X315848Y1994292D01*
X315590Y1994484D01*
X315228Y1994560D01*
X314867Y1994484D01*
X314557Y1994254D01*
X314402Y1993909D01*
Y1993525D01*
X314298Y1993295D01*
X314040Y1993104D01*
X313678Y1993027D01*
X313317Y1993142D01*
X313058Y1993410D01*
X312955Y1993717D01*
X313058Y1994024D01*
X313317Y1994292D01*
X313678Y1994407D01*
X314040Y1994330D01*
X314298Y1994139D01*
X314402Y1993909D01*
Y1993525D01*
X314557Y1993180D01*
X314867Y1992950D01*
X315228Y1992874D01*
X315590Y1992950D01*
X315848Y1993142D01*
X316003Y1993449D01*
X316055Y1993717D01*
G01X316862Y2006607D02*
Y1996407D01*
X312262D01*
Y2006607D01*
X316862D01*
G01Y2001507D02*
X312262D01*
G01X328600Y-123333D02*
X329200Y-122533D01*
X329900Y-122133D01*
X330700Y-122000D01*
X331700Y-122267D01*
X332400Y-122933D01*
X332600Y-123733D01*
X332500Y-124534D01*
X332100Y-125200D01*
X330100Y-126533D01*
X329200Y-127467D01*
X328600Y-128800D01*
X328400Y-130000D01*
X332600D01*
G01X338500Y-122000D02*
X337700Y-122267D01*
X337100Y-122933D01*
X336700Y-123733D01*
X336400Y-124800D01*
X336300Y-126000D01*
X336400Y-127200D01*
X336700Y-128267D01*
X337100Y-129067D01*
X337700Y-129733D01*
X338500Y-130000D01*
X339300Y-129733D01*
X339900Y-129067D01*
X340300Y-128267D01*
X340600Y-127200D01*
X340700Y-126000D01*
X340600Y-124800D01*
X340300Y-123733D01*
X339900Y-122933D01*
X339300Y-122267D01*
X338500Y-122000D01*
G01X346500Y-130000D02*
Y-122000D01*
X345300Y-123600D01*
G01Y-130000D02*
X347700D01*
G01X352300Y-128400D02*
X352900Y-129333D01*
X353700Y-129867D01*
X354600Y-130000D01*
X355400Y-129867D01*
X356200Y-129200D01*
X356700Y-128400D01*
X356800Y-127600D01*
X356600Y-126667D01*
X355900Y-126000D01*
X355200Y-125733D01*
X354300D01*
G01X355200D02*
X355800Y-125333D01*
X356300Y-124667D01*
X356500Y-123867D01*
X356300Y-123067D01*
X355800Y-122400D01*
X354900Y-122000D01*
X354000Y-122133D01*
X353100Y-122667D01*
G01X360700Y-130267D02*
X364300Y-122000D01*
G01X370500D02*
X369700Y-122267D01*
X369100Y-122933D01*
X368700Y-123733D01*
X368400Y-124800D01*
X368300Y-126000D01*
X368400Y-127200D01*
X368700Y-128267D01*
X369100Y-129067D01*
X369700Y-129733D01*
X370500Y-130000D01*
X371300Y-129733D01*
X371900Y-129067D01*
X372300Y-128267D01*
X372600Y-127200D01*
X372700Y-126000D01*
X372600Y-124800D01*
X372300Y-123733D01*
X371900Y-122933D01*
X371300Y-122267D01*
X370500Y-122000D01*
G01X378500Y-130000D02*
Y-122000D01*
X377300Y-123600D01*
G01Y-130000D02*
X379700D01*
G01X384700Y-130267D02*
X388300Y-122000D01*
G01X394500D02*
X393700Y-122267D01*
X393100Y-122933D01*
X392700Y-123733D01*
X392400Y-124800D01*
X392300Y-126000D01*
X392400Y-127200D01*
X392700Y-128267D01*
X393100Y-129067D01*
X393700Y-129733D01*
X394500Y-130000D01*
X395300Y-129733D01*
X395900Y-129067D01*
X396300Y-128267D01*
X396600Y-127200D01*
X396700Y-126000D01*
X396600Y-124800D01*
X396300Y-123733D01*
X395900Y-122933D01*
X395300Y-122267D01*
X394500Y-122000D01*
G01X400800Y-129067D02*
X401500Y-129733D01*
X402300Y-130000D01*
X403100Y-129733D01*
X403800Y-128934D01*
X404300Y-127733D01*
X404500Y-126533D01*
Y-125067D01*
X404300Y-123867D01*
X403800Y-122800D01*
X403200Y-122267D01*
X402500Y-122000D01*
X401700Y-122267D01*
X401100Y-122800D01*
X400700Y-123600D01*
X400500Y-124667D01*
X400700Y-125600D01*
X401200Y-126533D01*
X401800Y-127067D01*
X402500Y-127200D01*
X403300Y-126934D01*
X403900Y-126267D01*
X404500Y-125067D01*
G01X328300Y-105000D02*
Y-97000D01*
X330300D01*
X331100Y-97400D01*
X331700Y-97933D01*
X332200Y-98733D01*
X332600Y-99667D01*
X332700Y-101000D01*
X332600Y-102333D01*
X332200Y-103267D01*
X331700Y-104067D01*
X331100Y-104600D01*
X330300Y-105000D01*
X328300D01*
G01X336000D02*
X338500Y-97000D01*
X341000Y-105000D01*
G01X340100Y-102200D02*
X336900D01*
G01X346500Y-97000D02*
Y-105000D01*
G01X344200Y-97000D02*
X348800D01*
G01X352600Y-101667D02*
X353300Y-100733D01*
X353900Y-100200D01*
X354700Y-99933D01*
X355400Y-100200D01*
X355900Y-100733D01*
X356300Y-101533D01*
X356400Y-102467D01*
X356300Y-103267D01*
X355900Y-104067D01*
X355300Y-104733D01*
X354600Y-105000D01*
X353800Y-104733D01*
X353100Y-103934D01*
X352700Y-102733D01*
X352600Y-101400D01*
X352800Y-99667D01*
X353100Y-98733D01*
X353600Y-97800D01*
X354300Y-97133D01*
X355000Y-97000D01*
X355700Y-97267D01*
X356200Y-97933D01*
G01X359900Y-105000D02*
Y-97000D01*
X362500Y-103667D01*
X365100Y-97000D01*
Y-105000D01*
G01X370500Y-97000D02*
Y-105000D01*
G01X368200Y-97000D02*
X372800D01*
G01X379300Y-100733D02*
X379700Y-100333D01*
X380000Y-99667D01*
X380200Y-98733D01*
X380000Y-97933D01*
X379600Y-97400D01*
X378900Y-97000D01*
X376200D01*
Y-105000D01*
X379500D01*
X380200Y-104467D01*
X380600Y-103667D01*
X380800Y-102733D01*
X380600Y-101800D01*
X380000Y-101000D01*
X379300Y-100733D01*
X376200D01*
G01X386500Y-105000D02*
X387200Y-104867D01*
X388000Y-104467D01*
X388500Y-103800D01*
X388700Y-102867D01*
X388500Y-101934D01*
X387900Y-101133D01*
X387000Y-100733D01*
X386000D01*
X385400Y-100467D01*
X384900Y-99800D01*
X384700Y-98867D01*
X385000Y-97933D01*
X385700Y-97267D01*
X386500Y-97000D01*
X387300Y-97267D01*
X388000Y-97933D01*
X388300Y-98867D01*
X388100Y-99800D01*
X387600Y-100467D01*
X387000Y-100733D01*
X386000D01*
X385100Y-101133D01*
X384500Y-101934D01*
X384300Y-102867D01*
X384500Y-103800D01*
X385000Y-104467D01*
X385800Y-104867D01*
X386500Y-105000D01*
G01X394500D02*
X395200Y-104867D01*
X396000Y-104467D01*
X396500Y-103800D01*
X396700Y-102867D01*
X396500Y-101934D01*
X395900Y-101133D01*
X395000Y-100733D01*
X394000D01*
X393400Y-100467D01*
X392900Y-99800D01*
X392700Y-98867D01*
X393000Y-97933D01*
X393700Y-97267D01*
X394500Y-97000D01*
X395300Y-97267D01*
X396000Y-97933D01*
X396300Y-98867D01*
X396100Y-99800D01*
X395600Y-100467D01*
X395000Y-100733D01*
X394000D01*
X393100Y-101133D01*
X392500Y-101934D01*
X392300Y-102867D01*
X392500Y-103800D01*
X393000Y-104467D01*
X393800Y-104867D01*
X394500Y-105000D01*
G01X400000D02*
X402500Y-97000D01*
X405000Y-105000D01*
G01X404100Y-102200D02*
X400900D01*
G01X410500Y-97000D02*
X409700Y-97267D01*
X409100Y-97933D01*
X408700Y-98733D01*
X408400Y-99800D01*
X408300Y-101000D01*
X408400Y-102200D01*
X408700Y-103267D01*
X409100Y-104067D01*
X409700Y-104733D01*
X410500Y-105000D01*
X411300Y-104733D01*
X411900Y-104067D01*
X412300Y-103267D01*
X412600Y-102200D01*
X412700Y-101000D01*
X412600Y-99800D01*
X412300Y-98733D01*
X411900Y-97933D01*
X411300Y-97267D01*
X410500Y-97000D01*
G01X318760Y14273D02*
Y17373D01*
X319680D01*
X319987Y17218D01*
X320217Y16856D01*
X320294Y16443D01*
X320217Y16030D01*
X320025Y15720D01*
X319680Y15565D01*
X318760D01*
G01X322627Y14273D02*
Y17373D01*
X322167Y16753D01*
G01Y14273D02*
X323087D01*
G01X325650D02*
X325727Y14945D01*
X325842Y15513D01*
X325995Y16030D01*
X326187Y16598D01*
X326494Y17373D01*
X324960D01*
G01X331842Y14000D02*
X332149Y13742D01*
X332494Y13587D01*
X332800D01*
X333107Y13742D01*
X333337Y14000D01*
X333452Y14362D01*
X333375Y14724D01*
X333184Y15034D01*
X332839Y15240D01*
X332379Y15344D01*
X332110Y15550D01*
X331995Y15912D01*
X332072Y16274D01*
X332264Y16532D01*
X332532Y16687D01*
X332800D01*
X333069Y16584D01*
X333299Y16325D01*
G01X335747Y13587D02*
Y16687D01*
X335287Y16067D01*
G01Y13587D02*
X336207D01*
G01X338119Y16170D02*
X338349Y16480D01*
X338617Y16635D01*
X338924Y16687D01*
X339307Y16584D01*
X339575Y16325D01*
X339652Y16015D01*
X339614Y15705D01*
X339460Y15447D01*
X338694Y14930D01*
X338349Y14569D01*
X338119Y14052D01*
X338042Y13587D01*
X339652D01*
G01X318930Y36708D02*
Y39808D01*
X319850D01*
X320157Y39653D01*
X320387Y39291D01*
X320464Y38878D01*
X320387Y38465D01*
X320195Y38155D01*
X319850Y38000D01*
X318930D01*
G01X322797Y36708D02*
Y39808D01*
X322337Y39188D01*
G01Y36708D02*
X323257D01*
G01X325169Y38000D02*
X325437Y38361D01*
X325667Y38568D01*
X325974Y38671D01*
X326242Y38568D01*
X326434Y38361D01*
X326587Y38051D01*
X326625Y37690D01*
X326587Y37380D01*
X326434Y37070D01*
X326204Y36811D01*
X325935Y36708D01*
X325629Y36811D01*
X325360Y37121D01*
X325207Y37586D01*
X325169Y38103D01*
X325245Y38775D01*
X325360Y39136D01*
X325552Y39498D01*
X325820Y39756D01*
X326089Y39808D01*
X326357Y39705D01*
X326549Y39446D01*
G01X334892Y39650D02*
X335199Y39392D01*
X335544Y39237D01*
X335850D01*
X336157Y39392D01*
X336387Y39650D01*
X336502Y40012D01*
X336425Y40374D01*
X336234Y40684D01*
X335889Y40890D01*
X335429Y40994D01*
X335160Y41200D01*
X335045Y41562D01*
X335122Y41924D01*
X335314Y42182D01*
X335582Y42337D01*
X335850D01*
X336119Y42234D01*
X336349Y41975D01*
G01X338797Y39237D02*
Y42337D01*
X338337Y41717D01*
G01Y39237D02*
X339257D01*
G01X316067Y73818D02*
X319067D01*
G01X319167Y76918D02*
Y70718D01*
X315967D01*
Y76918D01*
X319167D01*
G01X320505Y73818D02*
X323505D01*
G01X323605Y76918D02*
Y70718D01*
X320405D01*
Y76918D01*
X323605D01*
G01X316046Y82706D02*
X315891Y82476D01*
X315788Y82208D01*
Y81901D01*
X315943Y81556D01*
X316201Y81288D01*
X316511Y81096D01*
X317028Y80943D01*
X317493Y80905D01*
X317958Y80981D01*
X318268Y81096D01*
X318578Y81326D01*
X318785Y81595D01*
X318888Y81863D01*
Y82131D01*
X318785Y82400D01*
X318630Y82630D01*
X318423Y82821D01*
G01X317596Y84235D02*
X317235Y84503D01*
X317028Y84733D01*
X316925Y85040D01*
X317028Y85308D01*
X317235Y85500D01*
X317545Y85653D01*
X317906Y85691D01*
X318216Y85653D01*
X318526Y85500D01*
X318785Y85270D01*
X318888Y85001D01*
X318785Y84695D01*
X318475Y84426D01*
X318010Y84273D01*
X317493Y84235D01*
X316821Y84311D01*
X316460Y84426D01*
X316098Y84618D01*
X315840Y84886D01*
X315788Y85155D01*
X315891Y85423D01*
X316150Y85615D01*
G01X320927Y82706D02*
X320772Y82476D01*
X320669Y82208D01*
Y81901D01*
X320824Y81556D01*
X321082Y81288D01*
X321392Y81096D01*
X321909Y80943D01*
X322374Y80905D01*
X322839Y80981D01*
X323149Y81096D01*
X323459Y81326D01*
X323666Y81595D01*
X323769Y81863D01*
Y82131D01*
X323666Y82400D01*
X323511Y82630D01*
X323304Y82821D01*
G01X323769Y84886D02*
X323097Y84963D01*
X322529Y85078D01*
X322012Y85231D01*
X321444Y85423D01*
X320669Y85730D01*
Y84196D01*
G01X335076Y144466D02*
Y147566D01*
G01X336686D02*
Y144466D01*
G01Y146016D02*
X335076D01*
G01X338981Y144466D02*
Y147566D01*
X338521Y146946D01*
G01Y144466D02*
X339441D01*
G01X341353Y147049D02*
X341583Y147359D01*
X341851Y147514D01*
X342158Y147566D01*
X342541Y147463D01*
X342809Y147204D01*
X342886Y146894D01*
X342848Y146584D01*
X342694Y146326D01*
X341928Y145809D01*
X341583Y145448D01*
X341353Y144931D01*
X341276Y144466D01*
X342886D01*
G01X318706Y171275D02*
Y174375D01*
X319626D01*
X319933Y174220D01*
X320163Y173858D01*
X320240Y173445D01*
X320163Y173032D01*
X319971Y172722D01*
X319626Y172567D01*
X318706D01*
G01X322573Y171275D02*
Y174375D01*
X322113Y173755D01*
G01Y171275D02*
X323033D01*
G01X325596D02*
X325673Y171947D01*
X325788Y172515D01*
X325941Y173032D01*
X326133Y173600D01*
X326440Y174375D01*
X324906D01*
G01X334851Y171293D02*
X335158Y171035D01*
X335503Y170880D01*
X335809D01*
X336116Y171035D01*
X336346Y171293D01*
X336461Y171655D01*
X336384Y172017D01*
X336193Y172327D01*
X335848Y172533D01*
X335388Y172637D01*
X335119Y172843D01*
X335004Y173205D01*
X335081Y173567D01*
X335273Y173825D01*
X335541Y173980D01*
X335809D01*
X336078Y173877D01*
X336308Y173618D01*
G01X338756Y170880D02*
Y173980D01*
X338296Y173360D01*
G01Y170880D02*
X339216D01*
G01X341128Y173463D02*
X341358Y173773D01*
X341626Y173928D01*
X341933Y173980D01*
X342316Y173877D01*
X342584Y173618D01*
X342661Y173308D01*
X342623Y172998D01*
X342469Y172740D01*
X341703Y172223D01*
X341358Y171862D01*
X341128Y171345D01*
X341051Y170880D01*
X342661D01*
G01X322258Y233377D02*
Y236477D01*
X323178D01*
X323485Y236322D01*
X323715Y235960D01*
X323792Y235547D01*
X323715Y235134D01*
X323523Y234824D01*
X323178Y234669D01*
X322258D01*
G01X326125Y233377D02*
Y236477D01*
X325665Y235857D01*
G01Y233377D02*
X326585D01*
G01X328497Y234669D02*
X328765Y235030D01*
X328995Y235237D01*
X329302Y235340D01*
X329570Y235237D01*
X329762Y235030D01*
X329915Y234720D01*
X329953Y234359D01*
X329915Y234049D01*
X329762Y233739D01*
X329532Y233480D01*
X329263Y233377D01*
X328957Y233480D01*
X328688Y233790D01*
X328535Y234255D01*
X328497Y234772D01*
X328573Y235444D01*
X328688Y235805D01*
X328880Y236167D01*
X329148Y236425D01*
X329417Y236477D01*
X329685Y236374D01*
X329877Y236115D01*
G01X335826Y231425D02*
X336133Y231167D01*
X336478Y231012D01*
X336784D01*
X337091Y231167D01*
X337321Y231425D01*
X337436Y231787D01*
X337359Y232149D01*
X337168Y232459D01*
X336823Y232665D01*
X336363Y232769D01*
X336094Y232975D01*
X335979Y233337D01*
X336056Y233699D01*
X336248Y233957D01*
X336516Y234112D01*
X336784D01*
X337053Y234009D01*
X337283Y233750D01*
G01X339731Y231012D02*
Y234112D01*
X339271Y233492D01*
G01Y231012D02*
X340191D01*
G01X320474Y346510D02*
Y349610D01*
X321394D01*
X321701Y349455D01*
X321931Y349093D01*
X322008Y348680D01*
X321931Y348267D01*
X321739Y347957D01*
X321394Y347802D01*
X320474D01*
G01X324341Y346510D02*
Y349610D01*
X323881Y348990D01*
G01Y346510D02*
X324801D01*
G01X327364D02*
X327441Y347182D01*
X327556Y347750D01*
X327709Y348267D01*
X327901Y348835D01*
X328208Y349610D01*
X326674D01*
G01X333758Y345232D02*
X334065Y344974D01*
X334410Y344819D01*
X334716D01*
X335023Y344974D01*
X335253Y345232D01*
X335368Y345594D01*
X335291Y345956D01*
X335100Y346266D01*
X334755Y346472D01*
X334295Y346576D01*
X334026Y346782D01*
X333911Y347144D01*
X333988Y347506D01*
X334180Y347764D01*
X334448Y347919D01*
X334716D01*
X334985Y347816D01*
X335215Y347557D01*
G01X337663Y344819D02*
Y347919D01*
X337203Y347299D01*
G01Y344819D02*
X338123D01*
G01X340035Y347402D02*
X340265Y347712D01*
X340533Y347867D01*
X340840Y347919D01*
X341223Y347816D01*
X341491Y347557D01*
X341568Y347247D01*
X341530Y346937D01*
X341376Y346679D01*
X340610Y346162D01*
X340265Y345801D01*
X340035Y345284D01*
X339958Y344819D01*
X341568D01*
G01X318429Y408605D02*
Y411705D01*
X319349D01*
X319656Y411550D01*
X319886Y411188D01*
X319963Y410775D01*
X319886Y410362D01*
X319694Y410052D01*
X319349Y409897D01*
X318429D01*
G01X322296Y408605D02*
Y411705D01*
X321836Y411085D01*
G01Y408605D02*
X322756D01*
G01X324668Y409897D02*
X324936Y410258D01*
X325166Y410465D01*
X325473Y410568D01*
X325741Y410465D01*
X325933Y410258D01*
X326086Y409948D01*
X326124Y409587D01*
X326086Y409277D01*
X325933Y408967D01*
X325703Y408708D01*
X325434Y408605D01*
X325128Y408708D01*
X324859Y409018D01*
X324706Y409483D01*
X324668Y410000D01*
X324744Y410672D01*
X324859Y411033D01*
X325051Y411395D01*
X325319Y411653D01*
X325588Y411705D01*
X325856Y411602D01*
X326048Y411343D01*
G01X334843Y406941D02*
X335150Y406683D01*
X335495Y406528D01*
X335801D01*
X336108Y406683D01*
X336338Y406941D01*
X336453Y407303D01*
X336376Y407665D01*
X336185Y407975D01*
X335840Y408181D01*
X335380Y408285D01*
X335111Y408491D01*
X334996Y408853D01*
X335073Y409215D01*
X335265Y409473D01*
X335533Y409628D01*
X335801D01*
X336070Y409525D01*
X336300Y409266D01*
G01X338748Y406528D02*
Y409628D01*
X338288Y409008D01*
G01Y406528D02*
X339208D01*
G01X327785Y518623D02*
Y521723D01*
X328705D01*
X329012Y521568D01*
X329242Y521206D01*
X329319Y520793D01*
X329242Y520380D01*
X329050Y520070D01*
X328705Y519915D01*
X327785D01*
G01X331652Y518623D02*
Y521723D01*
X331192Y521103D01*
G01Y518623D02*
X332112D01*
G01X334675D02*
X334752Y519295D01*
X334867Y519863D01*
X335020Y520380D01*
X335212Y520948D01*
X335519Y521723D01*
X333985D01*
G01X338404Y521009D02*
X338711Y520751D01*
X339056Y520596D01*
X339362D01*
X339669Y520751D01*
X339899Y521009D01*
X340014Y521371D01*
X339937Y521733D01*
X339746Y522043D01*
X339401Y522249D01*
X338941Y522353D01*
X338672Y522559D01*
X338557Y522921D01*
X338634Y523283D01*
X338826Y523541D01*
X339094Y523696D01*
X339362D01*
X339631Y523593D01*
X339861Y523334D01*
G01X342309Y520596D02*
Y523696D01*
X341849Y523076D01*
G01Y520596D02*
X342769D01*
G01X344681Y523179D02*
X344911Y523489D01*
X345179Y523644D01*
X345486Y523696D01*
X345869Y523593D01*
X346137Y523334D01*
X346214Y523024D01*
X346176Y522714D01*
X346022Y522456D01*
X345256Y521939D01*
X344911Y521578D01*
X344681Y521061D01*
X344604Y520596D01*
X346214D01*
G01X318311Y579671D02*
Y582771D01*
X319231D01*
X319538Y582616D01*
X319768Y582254D01*
X319845Y581841D01*
X319768Y581428D01*
X319576Y581118D01*
X319231Y580963D01*
X318311D01*
G01X322178Y579671D02*
Y582771D01*
X321718Y582151D01*
G01Y579671D02*
X322638D01*
G01X324550Y580963D02*
X324818Y581324D01*
X325048Y581531D01*
X325355Y581634D01*
X325623Y581531D01*
X325815Y581324D01*
X325968Y581014D01*
X326006Y580653D01*
X325968Y580343D01*
X325815Y580033D01*
X325585Y579774D01*
X325316Y579671D01*
X325010Y579774D01*
X324741Y580084D01*
X324588Y580549D01*
X324550Y581066D01*
X324626Y581738D01*
X324741Y582099D01*
X324933Y582461D01*
X325201Y582719D01*
X325470Y582771D01*
X325738Y582668D01*
X325930Y582409D01*
G01X334652Y582055D02*
X334959Y581797D01*
X335304Y581642D01*
X335610D01*
X335917Y581797D01*
X336147Y582055D01*
X336262Y582417D01*
X336185Y582779D01*
X335994Y583089D01*
X335649Y583295D01*
X335189Y583399D01*
X334920Y583605D01*
X334805Y583967D01*
X334882Y584329D01*
X335074Y584587D01*
X335342Y584742D01*
X335610D01*
X335879Y584639D01*
X336109Y584380D01*
G01X338557Y581642D02*
Y584742D01*
X338097Y584122D01*
G01Y581642D02*
X339017D01*
G01X318731Y693559D02*
Y696659D01*
X319651D01*
X319958Y696504D01*
X320188Y696142D01*
X320265Y695729D01*
X320188Y695316D01*
X319996Y695006D01*
X319651Y694851D01*
X318731D01*
G01X322598Y693559D02*
Y696659D01*
X322138Y696039D01*
G01Y693559D02*
X323058D01*
G01X325621D02*
X325698Y694231D01*
X325813Y694799D01*
X325966Y695316D01*
X326158Y695884D01*
X326465Y696659D01*
X324931D01*
G01X328547Y696690D02*
X328854Y696432D01*
X329199Y696277D01*
X329505D01*
X329812Y696432D01*
X330042Y696690D01*
X330157Y697052D01*
X330080Y697414D01*
X329889Y697724D01*
X329544Y697930D01*
X329084Y698034D01*
X328815Y698240D01*
X328700Y698602D01*
X328777Y698964D01*
X328969Y699222D01*
X329237Y699377D01*
X329505D01*
X329774Y699274D01*
X330004Y699015D01*
G01X332452Y696277D02*
Y699377D01*
X331992Y698757D01*
G01Y696277D02*
X332912D01*
G01X334824Y698860D02*
X335054Y699170D01*
X335322Y699325D01*
X335629Y699377D01*
X336012Y699274D01*
X336280Y699015D01*
X336357Y698705D01*
X336319Y698395D01*
X336165Y698137D01*
X335399Y697620D01*
X335054Y697259D01*
X334824Y696742D01*
X334747Y696277D01*
X336357D01*
G01X317016Y755587D02*
Y758687D01*
X317936D01*
X318243Y758532D01*
X318473Y758170D01*
X318550Y757757D01*
X318473Y757344D01*
X318281Y757034D01*
X317936Y756879D01*
X317016D01*
G01X320883Y755587D02*
Y758687D01*
X320423Y758067D01*
G01Y755587D02*
X321343D01*
G01X323255Y756879D02*
X323523Y757240D01*
X323753Y757447D01*
X324060Y757550D01*
X324328Y757447D01*
X324520Y757240D01*
X324673Y756930D01*
X324711Y756569D01*
X324673Y756259D01*
X324520Y755949D01*
X324290Y755690D01*
X324021Y755587D01*
X323715Y755690D01*
X323446Y756000D01*
X323293Y756465D01*
X323255Y756982D01*
X323331Y757654D01*
X323446Y758015D01*
X323638Y758377D01*
X323906Y758635D01*
X324175Y758687D01*
X324443Y758584D01*
X324635Y758325D01*
G01X335895Y756132D02*
X336202Y755874D01*
X336547Y755719D01*
X336853D01*
X337160Y755874D01*
X337390Y756132D01*
X337505Y756494D01*
X337428Y756856D01*
X337237Y757166D01*
X336892Y757372D01*
X336432Y757476D01*
X336163Y757682D01*
X336048Y758044D01*
X336125Y758406D01*
X336317Y758664D01*
X336585Y758819D01*
X336853D01*
X337122Y758716D01*
X337352Y758457D01*
G01X339800Y755719D02*
Y758819D01*
X339340Y758199D01*
G01Y755719D02*
X340260D01*
G01X318773Y870821D02*
Y873921D01*
X319693D01*
X320000Y873766D01*
X320230Y873404D01*
X320307Y872991D01*
X320230Y872578D01*
X320038Y872268D01*
X319693Y872113D01*
X318773D01*
G01X322640Y870821D02*
Y873921D01*
X322180Y873301D01*
G01Y870821D02*
X323100D01*
G01X325663D02*
X325740Y871493D01*
X325855Y872061D01*
X326008Y872578D01*
X326200Y873146D01*
X326507Y873921D01*
X324973D01*
G01X332256Y870816D02*
X332563Y870558D01*
X332908Y870403D01*
X333214D01*
X333521Y870558D01*
X333751Y870816D01*
X333866Y871178D01*
X333789Y871540D01*
X333598Y871850D01*
X333253Y872056D01*
X332793Y872160D01*
X332524Y872366D01*
X332409Y872728D01*
X332486Y873090D01*
X332678Y873348D01*
X332946Y873503D01*
X333214D01*
X333483Y873400D01*
X333713Y873141D01*
G01X336161Y870403D02*
Y873503D01*
X335701Y872883D01*
G01Y870403D02*
X336621D01*
G01X338533Y872986D02*
X338763Y873296D01*
X339031Y873451D01*
X339338Y873503D01*
X339721Y873400D01*
X339989Y873141D01*
X340066Y872831D01*
X340028Y872521D01*
X339874Y872263D01*
X339108Y871746D01*
X338763Y871385D01*
X338533Y870868D01*
X338456Y870403D01*
X340066D01*
G01X334448Y930858D02*
X334755Y930600D01*
X335100Y930445D01*
X335406D01*
X335713Y930600D01*
X335943Y930858D01*
X336058Y931220D01*
X335981Y931582D01*
X335790Y931892D01*
X335445Y932098D01*
X334985Y932202D01*
X334716Y932408D01*
X334601Y932770D01*
X334678Y933132D01*
X334870Y933390D01*
X335138Y933545D01*
X335406D01*
X335675Y933442D01*
X335905Y933183D01*
G01X338353Y930445D02*
Y933545D01*
X337893Y932925D01*
G01Y930445D02*
X338813D01*
G01X317127Y1045696D02*
Y1048796D01*
X318047D01*
X318354Y1048641D01*
X318584Y1048279D01*
X318661Y1047866D01*
X318584Y1047453D01*
X318392Y1047143D01*
X318047Y1046988D01*
X317127D01*
G01X320994Y1045696D02*
Y1048796D01*
X320534Y1048176D01*
G01Y1045696D02*
X321454D01*
G01X324017D02*
X324094Y1046368D01*
X324209Y1046936D01*
X324362Y1047453D01*
X324554Y1048021D01*
X324861Y1048796D01*
X323327D01*
G01X327088Y1045188D02*
X327395Y1044930D01*
X327740Y1044775D01*
X328046D01*
X328353Y1044930D01*
X328583Y1045188D01*
X328698Y1045550D01*
X328621Y1045912D01*
X328430Y1046222D01*
X328085Y1046428D01*
X327625Y1046532D01*
X327356Y1046738D01*
X327241Y1047100D01*
X327318Y1047462D01*
X327510Y1047720D01*
X327778Y1047875D01*
X328046D01*
X328315Y1047772D01*
X328545Y1047513D01*
G01X330993Y1044775D02*
Y1047875D01*
X330533Y1047255D01*
G01Y1044775D02*
X331453D01*
G01X333365Y1047358D02*
X333595Y1047668D01*
X333863Y1047823D01*
X334170Y1047875D01*
X334553Y1047772D01*
X334821Y1047513D01*
X334898Y1047203D01*
X334860Y1046893D01*
X334706Y1046635D01*
X333940Y1046118D01*
X333595Y1045757D01*
X333365Y1045240D01*
X333288Y1044775D01*
X334898D01*
G01X319882Y1105275D02*
Y1108375D01*
X320802D01*
X321109Y1108220D01*
X321339Y1107858D01*
X321416Y1107445D01*
X321339Y1107032D01*
X321147Y1106722D01*
X320802Y1106567D01*
X319882D01*
G01X323749Y1105275D02*
Y1108375D01*
X323289Y1107755D01*
G01Y1105275D02*
X324209D01*
G01X326121Y1106567D02*
X326389Y1106928D01*
X326619Y1107135D01*
X326926Y1107238D01*
X327194Y1107135D01*
X327386Y1106928D01*
X327539Y1106618D01*
X327577Y1106257D01*
X327539Y1105947D01*
X327386Y1105637D01*
X327156Y1105378D01*
X326887Y1105275D01*
X326581Y1105378D01*
X326312Y1105688D01*
X326159Y1106153D01*
X326121Y1106670D01*
X326197Y1107342D01*
X326312Y1107703D01*
X326504Y1108065D01*
X326772Y1108323D01*
X327041Y1108375D01*
X327309Y1108272D01*
X327501Y1108013D01*
G01X333506Y1105053D02*
X333813Y1104795D01*
X334158Y1104640D01*
X334464D01*
X334771Y1104795D01*
X335001Y1105053D01*
X335116Y1105415D01*
X335039Y1105777D01*
X334848Y1106087D01*
X334503Y1106293D01*
X334043Y1106397D01*
X333774Y1106603D01*
X333659Y1106965D01*
X333736Y1107327D01*
X333928Y1107585D01*
X334196Y1107740D01*
X334464D01*
X334733Y1107637D01*
X334963Y1107378D01*
G01X337411Y1104640D02*
Y1107740D01*
X336951Y1107120D01*
G01Y1104640D02*
X337871D01*
G01X321733Y1160666D02*
X315533D01*
Y1163866D01*
X321733D01*
Y1160666D01*
G01X321789Y1171204D02*
X315589D01*
Y1174404D01*
X321789D01*
Y1171204D01*
G01X317742Y1219580D02*
Y1222680D01*
X318662D01*
X318969Y1222525D01*
X319199Y1222163D01*
X319276Y1221750D01*
X319199Y1221337D01*
X319007Y1221027D01*
X318662Y1220872D01*
X317742D01*
G01X321609Y1219580D02*
Y1222680D01*
X321149Y1222060D01*
G01Y1219580D02*
X322069D01*
G01X324632D02*
X324709Y1220252D01*
X324824Y1220820D01*
X324977Y1221337D01*
X325169Y1221905D01*
X325476Y1222680D01*
X323942D01*
G01X330585Y1220931D02*
X330892Y1220673D01*
X331237Y1220518D01*
X331543D01*
X331850Y1220673D01*
X332080Y1220931D01*
X332195Y1221293D01*
X332118Y1221655D01*
X331927Y1221965D01*
X331582Y1222171D01*
X331122Y1222275D01*
X330853Y1222481D01*
X330738Y1222843D01*
X330815Y1223205D01*
X331007Y1223463D01*
X331275Y1223618D01*
X331543D01*
X331812Y1223515D01*
X332042Y1223256D01*
G01X334490Y1220518D02*
Y1223618D01*
X334030Y1222998D01*
G01Y1220518D02*
X334950D01*
G01X336862Y1223101D02*
X337092Y1223411D01*
X337360Y1223566D01*
X337667Y1223618D01*
X338050Y1223515D01*
X338318Y1223256D01*
X338395Y1222946D01*
X338357Y1222636D01*
X338203Y1222378D01*
X337437Y1221861D01*
X337092Y1221500D01*
X336862Y1220983D01*
X336785Y1220518D01*
X338395D01*
G01X319401Y1284348D02*
Y1287448D01*
X320321D01*
X320628Y1287293D01*
X320858Y1286931D01*
X320935Y1286518D01*
X320858Y1286105D01*
X320666Y1285795D01*
X320321Y1285640D01*
X319401D01*
G01X323268Y1284348D02*
Y1287448D01*
X322808Y1286828D01*
G01Y1284348D02*
X323728D01*
G01X325640Y1285640D02*
X325908Y1286001D01*
X326138Y1286208D01*
X326445Y1286311D01*
X326713Y1286208D01*
X326905Y1286001D01*
X327058Y1285691D01*
X327096Y1285330D01*
X327058Y1285020D01*
X326905Y1284710D01*
X326675Y1284451D01*
X326406Y1284348D01*
X326100Y1284451D01*
X325831Y1284761D01*
X325678Y1285226D01*
X325640Y1285743D01*
X325716Y1286415D01*
X325831Y1286776D01*
X326023Y1287138D01*
X326291Y1287396D01*
X326560Y1287448D01*
X326828Y1287345D01*
X327020Y1287086D01*
G01X335171Y1284761D02*
X335478Y1284503D01*
X335823Y1284348D01*
X336129D01*
X336436Y1284503D01*
X336666Y1284761D01*
X336781Y1285123D01*
X336704Y1285485D01*
X336513Y1285795D01*
X336168Y1286001D01*
X335708Y1286105D01*
X335439Y1286311D01*
X335324Y1286673D01*
X335401Y1287035D01*
X335593Y1287293D01*
X335861Y1287448D01*
X336129D01*
X336398Y1287345D01*
X336628Y1287086D01*
G01X339076Y1284348D02*
Y1287448D01*
X338616Y1286828D01*
G01Y1284348D02*
X339536D01*
G01X318713Y1394364D02*
Y1397464D01*
X319633D01*
X319940Y1397309D01*
X320170Y1396947D01*
X320247Y1396534D01*
X320170Y1396121D01*
X319978Y1395811D01*
X319633Y1395656D01*
X318713D01*
G01X322580Y1394364D02*
Y1397464D01*
X322120Y1396844D01*
G01Y1394364D02*
X323040D01*
G01X325603D02*
X325680Y1395036D01*
X325795Y1395604D01*
X325948Y1396121D01*
X326140Y1396689D01*
X326447Y1397464D01*
X324913D01*
G01X331265Y1395226D02*
X331572Y1394968D01*
X331917Y1394813D01*
X332223D01*
X332530Y1394968D01*
X332760Y1395226D01*
X332875Y1395588D01*
X332798Y1395950D01*
X332607Y1396260D01*
X332262Y1396466D01*
X331802Y1396570D01*
X331533Y1396776D01*
X331418Y1397138D01*
X331495Y1397500D01*
X331687Y1397758D01*
X331955Y1397913D01*
X332223D01*
X332492Y1397810D01*
X332722Y1397551D01*
G01X335170Y1394813D02*
Y1397913D01*
X334710Y1397293D01*
G01Y1394813D02*
X335630D01*
G01X337542Y1397396D02*
X337772Y1397706D01*
X338040Y1397861D01*
X338347Y1397913D01*
X338730Y1397810D01*
X338998Y1397551D01*
X339075Y1397241D01*
X339037Y1396931D01*
X338883Y1396673D01*
X338117Y1396156D01*
X337772Y1395795D01*
X337542Y1395278D01*
X337465Y1394813D01*
X339075D01*
G01X319890Y1454488D02*
Y1457588D01*
X320810D01*
X321117Y1457433D01*
X321347Y1457071D01*
X321424Y1456658D01*
X321347Y1456245D01*
X321155Y1455935D01*
X320810Y1455780D01*
X319890D01*
G01X323757Y1454488D02*
Y1457588D01*
X323297Y1456968D01*
G01Y1454488D02*
X324217D01*
G01X326129Y1455780D02*
X326397Y1456141D01*
X326627Y1456348D01*
X326934Y1456451D01*
X327202Y1456348D01*
X327394Y1456141D01*
X327547Y1455831D01*
X327585Y1455470D01*
X327547Y1455160D01*
X327394Y1454850D01*
X327164Y1454591D01*
X326895Y1454488D01*
X326589Y1454591D01*
X326320Y1454901D01*
X326167Y1455366D01*
X326129Y1455883D01*
X326205Y1456555D01*
X326320Y1456916D01*
X326512Y1457278D01*
X326780Y1457536D01*
X327049Y1457588D01*
X327317Y1457485D01*
X327509Y1457226D01*
G01X334686Y1456168D02*
X334993Y1455910D01*
X335338Y1455755D01*
X335644D01*
X335951Y1455910D01*
X336181Y1456168D01*
X336296Y1456530D01*
X336219Y1456892D01*
X336028Y1457202D01*
X335683Y1457408D01*
X335223Y1457512D01*
X334954Y1457718D01*
X334839Y1458080D01*
X334916Y1458442D01*
X335108Y1458700D01*
X335376Y1458855D01*
X335644D01*
X335913Y1458752D01*
X336143Y1458493D01*
G01X338591Y1455755D02*
Y1458855D01*
X338131Y1458235D01*
G01Y1455755D02*
X339051D01*
G01X320902Y1560148D02*
Y1563248D01*
X321822D01*
X322129Y1563093D01*
X322359Y1562731D01*
X322436Y1562318D01*
X322359Y1561905D01*
X322167Y1561595D01*
X321822Y1561440D01*
X320902D01*
G01X324769Y1560148D02*
Y1563248D01*
X324309Y1562628D01*
G01Y1560148D02*
X325229D01*
G01X327792D02*
X327869Y1560820D01*
X327984Y1561388D01*
X328137Y1561905D01*
X328329Y1562473D01*
X328636Y1563248D01*
X327102D01*
G01X333984Y1561485D02*
X334291Y1561227D01*
X334636Y1561072D01*
X334942D01*
X335249Y1561227D01*
X335479Y1561485D01*
X335594Y1561847D01*
X335517Y1562209D01*
X335326Y1562519D01*
X334981Y1562725D01*
X334521Y1562829D01*
X334252Y1563035D01*
X334137Y1563397D01*
X334214Y1563759D01*
X334406Y1564017D01*
X334674Y1564172D01*
X334942D01*
X335211Y1564069D01*
X335441Y1563810D01*
G01X337889Y1561072D02*
Y1564172D01*
X337429Y1563552D01*
G01Y1561072D02*
X338349D01*
G01X340261Y1563655D02*
X340491Y1563965D01*
X340759Y1564120D01*
X341066Y1564172D01*
X341449Y1564069D01*
X341717Y1563810D01*
X341794Y1563500D01*
X341756Y1563190D01*
X341602Y1562932D01*
X340836Y1562415D01*
X340491Y1562054D01*
X340261Y1561537D01*
X340184Y1561072D01*
X341794D01*
G01X318041Y1629604D02*
Y1632704D01*
X318961D01*
X319268Y1632549D01*
X319498Y1632187D01*
X319575Y1631774D01*
X319498Y1631361D01*
X319306Y1631051D01*
X318961Y1630896D01*
X318041D01*
G01X321908Y1629604D02*
Y1632704D01*
X321448Y1632084D01*
G01Y1629604D02*
X322368D01*
G01X324280Y1630896D02*
X324548Y1631257D01*
X324778Y1631464D01*
X325085Y1631567D01*
X325353Y1631464D01*
X325545Y1631257D01*
X325698Y1630947D01*
X325736Y1630586D01*
X325698Y1630276D01*
X325545Y1629966D01*
X325315Y1629707D01*
X325046Y1629604D01*
X324740Y1629707D01*
X324471Y1630017D01*
X324318Y1630482D01*
X324280Y1630999D01*
X324356Y1631671D01*
X324471Y1632032D01*
X324663Y1632394D01*
X324931Y1632652D01*
X325200Y1632704D01*
X325468Y1632601D01*
X325660Y1632342D01*
G01X333331Y1631204D02*
X333638Y1630946D01*
X333983Y1630791D01*
X334289D01*
X334596Y1630946D01*
X334826Y1631204D01*
X334941Y1631566D01*
X334864Y1631928D01*
X334673Y1632238D01*
X334328Y1632444D01*
X333868Y1632548D01*
X333599Y1632754D01*
X333484Y1633116D01*
X333561Y1633478D01*
X333753Y1633736D01*
X334021Y1633891D01*
X334289D01*
X334558Y1633788D01*
X334788Y1633529D01*
G01X337236Y1630791D02*
Y1633891D01*
X336776Y1633271D01*
G01Y1630791D02*
X337696D01*
G01X316858Y1744019D02*
Y1747119D01*
X317778D01*
X318085Y1746964D01*
X318315Y1746602D01*
X318392Y1746189D01*
X318315Y1745776D01*
X318123Y1745466D01*
X317778Y1745311D01*
X316858D01*
G01X320725Y1744019D02*
Y1747119D01*
X320265Y1746499D01*
G01Y1744019D02*
X321185D01*
G01X323748D02*
X323825Y1744691D01*
X323940Y1745259D01*
X324093Y1745776D01*
X324285Y1746344D01*
X324592Y1747119D01*
X323058D01*
G01X329536Y1744685D02*
X329843Y1744427D01*
X330188Y1744272D01*
X330494D01*
X330801Y1744427D01*
X331031Y1744685D01*
X331146Y1745047D01*
X331069Y1745409D01*
X330878Y1745719D01*
X330533Y1745925D01*
X330073Y1746029D01*
X329804Y1746235D01*
X329689Y1746597D01*
X329766Y1746959D01*
X329958Y1747217D01*
X330226Y1747372D01*
X330494D01*
X330763Y1747269D01*
X330993Y1747010D01*
G01X333441Y1744272D02*
Y1747372D01*
X332981Y1746752D01*
G01Y1744272D02*
X333901D01*
G01X335813Y1746855D02*
X336043Y1747165D01*
X336311Y1747320D01*
X336618Y1747372D01*
X337001Y1747269D01*
X337269Y1747010D01*
X337346Y1746700D01*
X337308Y1746390D01*
X337154Y1746132D01*
X336388Y1745615D01*
X336043Y1745254D01*
X335813Y1744737D01*
X335736Y1744272D01*
X337346D01*
G01X324400Y1804895D02*
Y1807995D01*
X325320D01*
X325627Y1807840D01*
X325857Y1807478D01*
X325934Y1807065D01*
X325857Y1806652D01*
X325665Y1806342D01*
X325320Y1806187D01*
X324400D01*
G01X328267Y1804895D02*
Y1807995D01*
X327807Y1807375D01*
G01Y1804895D02*
X328727D01*
G01X330639Y1806187D02*
X330907Y1806548D01*
X331137Y1806755D01*
X331444Y1806858D01*
X331712Y1806755D01*
X331904Y1806548D01*
X332057Y1806238D01*
X332095Y1805877D01*
X332057Y1805567D01*
X331904Y1805257D01*
X331674Y1804998D01*
X331405Y1804895D01*
X331099Y1804998D01*
X330830Y1805308D01*
X330677Y1805773D01*
X330639Y1806290D01*
X330715Y1806962D01*
X330830Y1807323D01*
X331022Y1807685D01*
X331290Y1807943D01*
X331559Y1807995D01*
X331827Y1807892D01*
X332019Y1807633D01*
G01X319800Y1918028D02*
Y1921128D01*
X320720D01*
X321027Y1920973D01*
X321257Y1920611D01*
X321334Y1920198D01*
X321257Y1919785D01*
X321065Y1919475D01*
X320720Y1919320D01*
X319800D01*
G01X323667Y1918028D02*
Y1921128D01*
X323207Y1920508D01*
G01Y1918028D02*
X324127D01*
G01X326690D02*
X326767Y1918700D01*
X326882Y1919268D01*
X327035Y1919785D01*
X327227Y1920353D01*
X327534Y1921128D01*
X326000D01*
G01X335050Y1918304D02*
X335357Y1918046D01*
X335702Y1917891D01*
X336008D01*
X336315Y1918046D01*
X336545Y1918304D01*
X336660Y1918666D01*
X336583Y1919028D01*
X336392Y1919338D01*
X336047Y1919544D01*
X335587Y1919648D01*
X335318Y1919854D01*
X335203Y1920216D01*
X335280Y1920578D01*
X335472Y1920836D01*
X335740Y1920991D01*
X336008D01*
X336277Y1920888D01*
X336507Y1920629D01*
G01X338955Y1917891D02*
Y1920991D01*
X338495Y1920371D01*
G01Y1917891D02*
X339415D01*
G01X341327Y1920474D02*
X341557Y1920784D01*
X341825Y1920939D01*
X342132Y1920991D01*
X342515Y1920888D01*
X342783Y1920629D01*
X342860Y1920319D01*
X342822Y1920009D01*
X342668Y1919751D01*
X341902Y1919234D01*
X341557Y1918873D01*
X341327Y1918356D01*
X341250Y1917891D01*
X342860D01*
G01X318470Y1988360D02*
X318315Y1988130D01*
X318212Y1987862D01*
Y1987555D01*
X318367Y1987210D01*
X318625Y1986942D01*
X318935Y1986750D01*
X319452Y1986597D01*
X319917Y1986559D01*
X320382Y1986635D01*
X320692Y1986750D01*
X321002Y1986980D01*
X321209Y1987249D01*
X321312Y1987517D01*
Y1987785D01*
X321209Y1988054D01*
X321054Y1988284D01*
X320847Y1988475D01*
G01X321312Y1990540D02*
X320640Y1990617D01*
X320072Y1990732D01*
X319555Y1990885D01*
X318987Y1991077D01*
X318212Y1991384D01*
Y1989850D01*
G01X320950Y1993065D02*
X321209Y1993334D01*
X321312Y1993640D01*
X321209Y1993947D01*
X320899Y1994215D01*
X320434Y1994407D01*
X319969Y1994484D01*
X319400D01*
X318935Y1994407D01*
X318522Y1994215D01*
X318315Y1993985D01*
X318212Y1993717D01*
X318315Y1993410D01*
X318522Y1993180D01*
X318832Y1993027D01*
X319245Y1992950D01*
X319607Y1993027D01*
X319969Y1993219D01*
X320175Y1993449D01*
X320227Y1993717D01*
X320124Y1994024D01*
X319865Y1994254D01*
X319400Y1994484D01*
G01X323096Y1988360D02*
X322941Y1988130D01*
X322838Y1987862D01*
Y1987555D01*
X322993Y1987210D01*
X323251Y1986942D01*
X323561Y1986750D01*
X324078Y1986597D01*
X324543Y1986559D01*
X325008Y1986635D01*
X325318Y1986750D01*
X325628Y1986980D01*
X325835Y1987249D01*
X325938Y1987517D01*
Y1987785D01*
X325835Y1988054D01*
X325680Y1988284D01*
X325473Y1988475D01*
G01X325938Y1990617D02*
X325886Y1990885D01*
X325731Y1991192D01*
X325473Y1991384D01*
X325111Y1991460D01*
X324750Y1991384D01*
X324440Y1991154D01*
X324285Y1990809D01*
Y1990425D01*
X324181Y1990195D01*
X323923Y1990004D01*
X323561Y1989927D01*
X323200Y1990042D01*
X322941Y1990310D01*
X322838Y1990617D01*
X322941Y1990924D01*
X323200Y1991192D01*
X323561Y1991307D01*
X323923Y1991230D01*
X324181Y1991039D01*
X324285Y1990809D01*
Y1990425D01*
X324440Y1990080D01*
X324750Y1989850D01*
X325111Y1989774D01*
X325473Y1989850D01*
X325731Y1990042D01*
X325886Y1990349D01*
X325938Y1990617D01*
G01X322838Y1993717D02*
X322941Y1993410D01*
X323200Y1993180D01*
X323510Y1993027D01*
X323923Y1992912D01*
X324388Y1992874D01*
X324853Y1992912D01*
X325266Y1993027D01*
X325576Y1993180D01*
X325835Y1993410D01*
X325938Y1993717D01*
X325835Y1994024D01*
X325576Y1994254D01*
X325266Y1994407D01*
X324853Y1994522D01*
X324388Y1994560D01*
X323923Y1994522D01*
X323510Y1994407D01*
X323200Y1994254D01*
X322941Y1994024D01*
X322838Y1993717D01*
G01X331095Y1981045D02*
Y1984145D01*
X332015D01*
X332322Y1983990D01*
X332552Y1983628D01*
X332629Y1983215D01*
X332552Y1982802D01*
X332360Y1982492D01*
X332015Y1982337D01*
X331095D01*
G01X334962Y1981045D02*
Y1984145D01*
X334502Y1983525D01*
G01Y1981045D02*
X335422D01*
G01X337334Y1982337D02*
X337602Y1982698D01*
X337832Y1982905D01*
X338139Y1983008D01*
X338407Y1982905D01*
X338599Y1982698D01*
X338752Y1982388D01*
X338790Y1982027D01*
X338752Y1981717D01*
X338599Y1981407D01*
X338369Y1981148D01*
X338100Y1981045D01*
X337794Y1981148D01*
X337525Y1981458D01*
X337372Y1981923D01*
X337334Y1982440D01*
X337410Y1983112D01*
X337525Y1983473D01*
X337717Y1983835D01*
X337985Y1984093D01*
X338254Y1984145D01*
X338522Y1984042D01*
X338714Y1983783D01*
G01X318545Y2000456D02*
X321545D01*
G01X321645Y2003556D02*
Y1997356D01*
X318445D01*
Y2003556D01*
X321645D01*
G01X323303Y2000456D02*
X326303D01*
G01X326403Y2003556D02*
Y1997356D01*
X323203D01*
Y2003556D01*
X326403D01*
G01X350500Y-72000D02*
Y-80000D01*
G01X348200Y-72000D02*
X352800D01*
G01X356600Y-76667D02*
X357300Y-75733D01*
X357900Y-75200D01*
X358700Y-74933D01*
X359400Y-75200D01*
X359900Y-75733D01*
X360300Y-76533D01*
X360400Y-77467D01*
X360300Y-78267D01*
X359900Y-79067D01*
X359300Y-79733D01*
X358600Y-80000D01*
X357800Y-79733D01*
X357100Y-78934D01*
X356700Y-77733D01*
X356600Y-76400D01*
X356800Y-74667D01*
X357100Y-73733D01*
X357600Y-72800D01*
X358300Y-72133D01*
X359000Y-72000D01*
X359700Y-72267D01*
X360200Y-72933D01*
G01X363900Y-80000D02*
Y-72000D01*
X366500Y-78667D01*
X369100Y-72000D01*
Y-80000D01*
G01X375100Y-76000D02*
X377100D01*
Y-78400D01*
X376500Y-79200D01*
X375800Y-79733D01*
X374800Y-80000D01*
X373800Y-79733D01*
X373100Y-79200D01*
X372500Y-78400D01*
X372100Y-77467D01*
X371900Y-76400D01*
Y-75467D01*
X372100Y-74667D01*
X372500Y-73733D01*
X373100Y-72933D01*
X373700Y-72400D01*
X374500Y-72000D01*
X375200D01*
X376000Y-72267D01*
X376600Y-72800D01*
G01X379500Y-82667D02*
X385500D01*
G01X388500Y-80000D02*
Y-72000D01*
X390900D01*
X391700Y-72400D01*
X392300Y-73333D01*
X392500Y-74400D01*
X392300Y-75467D01*
X391800Y-76267D01*
X390900Y-76667D01*
X388500D01*
G01X396300Y-80000D02*
Y-72000D01*
X398300D01*
X399100Y-72400D01*
X399700Y-72933D01*
X400200Y-73733D01*
X400600Y-74667D01*
X400700Y-76000D01*
X400600Y-77333D01*
X400200Y-78267D01*
X399700Y-79067D01*
X399100Y-79600D01*
X398300Y-80000D01*
X396300D01*
G01X407300Y-75733D02*
X407700Y-75333D01*
X408000Y-74667D01*
X408200Y-73733D01*
X408000Y-72933D01*
X407600Y-72400D01*
X406900Y-72000D01*
X404200D01*
Y-80000D01*
X407500D01*
X408200Y-79467D01*
X408600Y-78667D01*
X408800Y-77733D01*
X408600Y-76800D01*
X408000Y-76000D01*
X407300Y-75733D01*
X404200D01*
G01X411500Y-82667D02*
X417500D01*
G01X420000Y-80000D02*
X422500Y-72000D01*
X425000Y-80000D01*
G01X424100Y-77200D02*
X420900D01*
G01X427500Y-82667D02*
X433500D01*
G01X439300Y-75733D02*
X439700Y-75333D01*
X440000Y-74667D01*
X440200Y-73733D01*
X440000Y-72933D01*
X439600Y-72400D01*
X438900Y-72000D01*
X436200D01*
Y-80000D01*
X439500D01*
X440200Y-79467D01*
X440600Y-78667D01*
X440800Y-77733D01*
X440600Y-76800D01*
X440000Y-76000D01*
X439300Y-75733D01*
X436200D01*
G01X444300Y-80000D02*
Y-72000D01*
X446300D01*
X447100Y-72400D01*
X447700Y-72933D01*
X448200Y-73733D01*
X448600Y-74667D01*
X448700Y-76000D01*
X448600Y-77333D01*
X448200Y-78267D01*
X447700Y-79067D01*
X447100Y-79600D01*
X446300Y-80000D01*
X444300D01*
G01X359570Y12643D02*
X359877Y12385D01*
X360222Y12230D01*
X360528D01*
X360835Y12385D01*
X361065Y12643D01*
X361180Y13005D01*
X361103Y13367D01*
X360912Y13677D01*
X360567Y13883D01*
X360107Y13987D01*
X359838Y14193D01*
X359723Y14555D01*
X359800Y14917D01*
X359992Y15175D01*
X360260Y15330D01*
X360528D01*
X360797Y15227D01*
X361027Y14968D01*
G01X363398Y12230D02*
X363475Y12902D01*
X363590Y13470D01*
X363743Y13987D01*
X363935Y14555D01*
X364242Y15330D01*
X362708D01*
G01X359568Y38053D02*
X359875Y37795D01*
X360220Y37640D01*
X360526D01*
X360833Y37795D01*
X361063Y38053D01*
X361178Y38415D01*
X361101Y38777D01*
X360910Y39087D01*
X360565Y39293D01*
X360105Y39397D01*
X359836Y39603D01*
X359721Y39965D01*
X359798Y40327D01*
X359990Y40585D01*
X360258Y40740D01*
X360526D01*
X360795Y40637D01*
X361025Y40378D01*
G01X362745Y38932D02*
X363013Y39293D01*
X363243Y39500D01*
X363550Y39603D01*
X363818Y39500D01*
X364010Y39293D01*
X364163Y38983D01*
X364201Y38622D01*
X364163Y38312D01*
X364010Y38002D01*
X363780Y37743D01*
X363511Y37640D01*
X363205Y37743D01*
X362936Y38053D01*
X362783Y38518D01*
X362745Y39035D01*
X362821Y39707D01*
X362936Y40068D01*
X363128Y40430D01*
X363396Y40688D01*
X363665Y40740D01*
X363933Y40637D01*
X364125Y40378D01*
G01X378842Y78780D02*
G03I-19000J0D01*
G01X339987Y97980D02*
Y101080D01*
G01X341597D02*
Y97980D01*
G01Y99530D02*
X339987D01*
G01X343164Y100563D02*
X343394Y100873D01*
X343662Y101028D01*
X343969Y101080D01*
X344352Y100977D01*
X344620Y100718D01*
X344697Y100408D01*
X344659Y100098D01*
X344505Y99840D01*
X343739Y99323D01*
X343394Y98962D01*
X343164Y98445D01*
X343087Y97980D01*
X344697D01*
G01X346149Y98445D02*
X346379Y98187D01*
X346647Y98032D01*
X346992Y97980D01*
X347337Y98083D01*
X347605Y98290D01*
X347797Y98652D01*
X347835Y99065D01*
X347759Y99478D01*
X347567Y99737D01*
X347299Y99943D01*
X347030Y99995D01*
X346762Y99943D01*
X346417Y99737D01*
X346532Y101080D01*
X347567D01*
G01X361698Y170078D02*
X362005Y169820D01*
X362350Y169665D01*
X362656D01*
X362963Y169820D01*
X363193Y170078D01*
X363308Y170440D01*
X363231Y170802D01*
X363040Y171112D01*
X362695Y171318D01*
X362235Y171422D01*
X361966Y171628D01*
X361851Y171990D01*
X361928Y172352D01*
X362120Y172610D01*
X362388Y172765D01*
X362656D01*
X362925Y172662D01*
X363155Y172403D01*
G01X365526Y169665D02*
X365603Y170337D01*
X365718Y170905D01*
X365871Y171422D01*
X366063Y171990D01*
X366370Y172765D01*
X364836D01*
G01X359295Y229963D02*
X359602Y229705D01*
X359947Y229550D01*
X360253D01*
X360560Y229705D01*
X360790Y229963D01*
X360905Y230325D01*
X360828Y230687D01*
X360637Y230997D01*
X360292Y231203D01*
X359832Y231307D01*
X359563Y231513D01*
X359448Y231875D01*
X359525Y232237D01*
X359717Y232495D01*
X359985Y232650D01*
X360253D01*
X360522Y232547D01*
X360752Y232288D01*
G01X362472Y230842D02*
X362740Y231203D01*
X362970Y231410D01*
X363277Y231513D01*
X363545Y231410D01*
X363737Y231203D01*
X363890Y230893D01*
X363928Y230532D01*
X363890Y230222D01*
X363737Y229912D01*
X363507Y229653D01*
X363238Y229550D01*
X362932Y229653D01*
X362663Y229963D01*
X362510Y230428D01*
X362472Y230945D01*
X362548Y231617D01*
X362663Y231978D01*
X362855Y232340D01*
X363123Y232598D01*
X363392Y232650D01*
X363660Y232547D01*
X363852Y232288D01*
G01X378842Y253780D02*
G03I-19000J0D01*
G01X339987Y272980D02*
Y276080D01*
G01X341597D02*
Y272980D01*
G01Y274530D02*
X339987D01*
G01X343892Y272980D02*
Y276080D01*
X343432Y275460D01*
G01Y272980D02*
X344352D01*
G01X346264Y274272D02*
X346532Y274633D01*
X346762Y274840D01*
X347069Y274943D01*
X347337Y274840D01*
X347529Y274633D01*
X347682Y274323D01*
X347720Y273962D01*
X347682Y273652D01*
X347529Y273342D01*
X347299Y273083D01*
X347030Y272980D01*
X346724Y273083D01*
X346455Y273393D01*
X346302Y273858D01*
X346264Y274375D01*
X346340Y275047D01*
X346455Y275408D01*
X346647Y275770D01*
X346915Y276028D01*
X347184Y276080D01*
X347452Y275977D01*
X347644Y275718D01*
G01X362425Y344946D02*
X362732Y344688D01*
X363077Y344533D01*
X363383D01*
X363690Y344688D01*
X363920Y344946D01*
X364035Y345308D01*
X363958Y345670D01*
X363767Y345980D01*
X363422Y346186D01*
X362962Y346290D01*
X362693Y346496D01*
X362578Y346858D01*
X362655Y347220D01*
X362847Y347478D01*
X363115Y347633D01*
X363383D01*
X363652Y347530D01*
X363882Y347271D01*
G01X366253Y344533D02*
X366330Y345205D01*
X366445Y345773D01*
X366598Y346290D01*
X366790Y346858D01*
X367097Y347633D01*
X365563D01*
G01X359973Y405493D02*
X360280Y405235D01*
X360625Y405080D01*
X360931D01*
X361238Y405235D01*
X361468Y405493D01*
X361583Y405855D01*
X361506Y406217D01*
X361315Y406527D01*
X360970Y406733D01*
X360510Y406837D01*
X360241Y407043D01*
X360126Y407405D01*
X360203Y407767D01*
X360395Y408025D01*
X360663Y408180D01*
X360931D01*
X361200Y408077D01*
X361430Y407818D01*
G01X363150Y406372D02*
X363418Y406733D01*
X363648Y406940D01*
X363955Y407043D01*
X364223Y406940D01*
X364415Y406733D01*
X364568Y406423D01*
X364606Y406062D01*
X364568Y405752D01*
X364415Y405442D01*
X364185Y405183D01*
X363916Y405080D01*
X363610Y405183D01*
X363341Y405493D01*
X363188Y405958D01*
X363150Y406475D01*
X363226Y407147D01*
X363341Y407508D01*
X363533Y407870D01*
X363801Y408128D01*
X364070Y408180D01*
X364338Y408077D01*
X364530Y407818D01*
G01X378842Y428779D02*
G03I-19000J0D01*
G01X339987Y447979D02*
Y451079D01*
G01X341597D02*
Y447979D01*
G01Y449529D02*
X339987D01*
G01X343892Y447979D02*
Y451079D01*
X343432Y450459D01*
G01Y447979D02*
X344352D01*
G01X346915D02*
X346992Y448651D01*
X347107Y449219D01*
X347260Y449736D01*
X347452Y450304D01*
X347759Y451079D01*
X346225D01*
G01X360116Y519148D02*
X360423Y518890D01*
X360768Y518735D01*
X361074D01*
X361381Y518890D01*
X361611Y519148D01*
X361726Y519510D01*
X361649Y519872D01*
X361458Y520182D01*
X361113Y520388D01*
X360653Y520492D01*
X360384Y520698D01*
X360269Y521060D01*
X360346Y521422D01*
X360538Y521680D01*
X360806Y521835D01*
X361074D01*
X361343Y521732D01*
X361573Y521473D01*
G01X363944Y518735D02*
X364021Y519407D01*
X364136Y519975D01*
X364289Y520492D01*
X364481Y521060D01*
X364788Y521835D01*
X363254D01*
G01X358789Y580593D02*
X359096Y580335D01*
X359441Y580180D01*
X359747D01*
X360054Y580335D01*
X360284Y580593D01*
X360399Y580955D01*
X360322Y581317D01*
X360131Y581627D01*
X359786Y581833D01*
X359326Y581937D01*
X359057Y582143D01*
X358942Y582505D01*
X359019Y582867D01*
X359211Y583125D01*
X359479Y583280D01*
X359747D01*
X360016Y583177D01*
X360246Y582918D01*
G01X361966Y581472D02*
X362234Y581833D01*
X362464Y582040D01*
X362771Y582143D01*
X363039Y582040D01*
X363231Y581833D01*
X363384Y581523D01*
X363422Y581162D01*
X363384Y580852D01*
X363231Y580542D01*
X363001Y580283D01*
X362732Y580180D01*
X362426Y580283D01*
X362157Y580593D01*
X362004Y581058D01*
X361966Y581575D01*
X362042Y582247D01*
X362157Y582608D01*
X362349Y582970D01*
X362617Y583228D01*
X362886Y583280D01*
X363154Y583177D01*
X363346Y582918D01*
G01X378842Y603779D02*
G03I-19000J0D01*
G01X339987Y622979D02*
Y626079D01*
G01X341597D02*
Y622979D01*
G01Y624529D02*
X339987D01*
G01X343164Y625562D02*
X343394Y625872D01*
X343662Y626027D01*
X343969Y626079D01*
X344352Y625976D01*
X344620Y625717D01*
X344697Y625407D01*
X344659Y625097D01*
X344505Y624839D01*
X343739Y624322D01*
X343394Y623961D01*
X343164Y623444D01*
X343087Y622979D01*
X344697D01*
G01X346264Y625562D02*
X346494Y625872D01*
X346762Y626027D01*
X347069Y626079D01*
X347452Y625976D01*
X347720Y625717D01*
X347797Y625407D01*
X347759Y625097D01*
X347605Y624839D01*
X346839Y624322D01*
X346494Y623961D01*
X346264Y623444D01*
X346187Y622979D01*
X347797D01*
G01X358131Y755211D02*
X358438Y754953D01*
X358783Y754798D01*
X359089D01*
X359396Y754953D01*
X359626Y755211D01*
X359741Y755573D01*
X359664Y755935D01*
X359473Y756245D01*
X359128Y756451D01*
X358668Y756555D01*
X358399Y756761D01*
X358284Y757123D01*
X358361Y757485D01*
X358553Y757743D01*
X358821Y757898D01*
X359089D01*
X359358Y757795D01*
X359588Y757536D01*
G01X361308Y756090D02*
X361576Y756451D01*
X361806Y756658D01*
X362113Y756761D01*
X362381Y756658D01*
X362573Y756451D01*
X362726Y756141D01*
X362764Y755780D01*
X362726Y755470D01*
X362573Y755160D01*
X362343Y754901D01*
X362074Y754798D01*
X361768Y754901D01*
X361499Y755211D01*
X361346Y755676D01*
X361308Y756193D01*
X361384Y756865D01*
X361499Y757226D01*
X361691Y757588D01*
X361959Y757846D01*
X362228Y757898D01*
X362496Y757795D01*
X362688Y757536D01*
G01X378842Y778780D02*
G03I-19000J0D01*
G01X339987Y797980D02*
Y801080D01*
G01X341597D02*
Y797980D01*
G01Y799530D02*
X339987D01*
G01X343164Y800563D02*
X343394Y800873D01*
X343662Y801028D01*
X343969Y801080D01*
X344352Y800977D01*
X344620Y800718D01*
X344697Y800408D01*
X344659Y800098D01*
X344505Y799840D01*
X343739Y799323D01*
X343394Y798962D01*
X343164Y798445D01*
X343087Y797980D01*
X344697D01*
G01X346992Y801080D02*
X346685Y800977D01*
X346455Y800718D01*
X346302Y800408D01*
X346187Y799995D01*
X346149Y799530D01*
X346187Y799065D01*
X346302Y798652D01*
X346455Y798342D01*
X346685Y798083D01*
X346992Y797980D01*
X347299Y798083D01*
X347529Y798342D01*
X347682Y798652D01*
X347797Y799065D01*
X347835Y799530D01*
X347797Y799995D01*
X347682Y800408D01*
X347529Y800718D01*
X347299Y800977D01*
X346992Y801080D01*
G01X359311Y869995D02*
X359618Y869737D01*
X359963Y869582D01*
X360269D01*
X360576Y869737D01*
X360806Y869995D01*
X360921Y870357D01*
X360844Y870719D01*
X360653Y871029D01*
X360308Y871235D01*
X359848Y871339D01*
X359579Y871545D01*
X359464Y871907D01*
X359541Y872269D01*
X359733Y872527D01*
X360001Y872682D01*
X360269D01*
X360538Y872579D01*
X360768Y872320D01*
G01X363139Y869582D02*
X363216Y870254D01*
X363331Y870822D01*
X363484Y871339D01*
X363676Y871907D01*
X363983Y872682D01*
X362449D01*
G01X361026Y930332D02*
X361333Y930074D01*
X361678Y929919D01*
X361984D01*
X362291Y930074D01*
X362521Y930332D01*
X362636Y930694D01*
X362559Y931056D01*
X362368Y931366D01*
X362023Y931572D01*
X361563Y931676D01*
X361294Y931882D01*
X361179Y932244D01*
X361256Y932606D01*
X361448Y932864D01*
X361716Y933019D01*
X361984D01*
X362253Y932916D01*
X362483Y932657D01*
G01X364203Y931211D02*
X364471Y931572D01*
X364701Y931779D01*
X365008Y931882D01*
X365276Y931779D01*
X365468Y931572D01*
X365621Y931262D01*
X365659Y930901D01*
X365621Y930591D01*
X365468Y930281D01*
X365238Y930022D01*
X364969Y929919D01*
X364663Y930022D01*
X364394Y930332D01*
X364241Y930797D01*
X364203Y931314D01*
X364279Y931986D01*
X364394Y932347D01*
X364586Y932709D01*
X364854Y932967D01*
X365123Y933019D01*
X365391Y932916D01*
X365583Y932657D01*
G01X378842Y953780D02*
G03I-19000J0D01*
G01X339987Y972980D02*
Y976080D01*
G01X341597D02*
Y972980D01*
G01Y974530D02*
X339987D01*
G01X343892Y972980D02*
Y976080D01*
X343432Y975460D01*
G01Y972980D02*
X344352D01*
G01X346992D02*
X347260Y973032D01*
X347567Y973187D01*
X347759Y973445D01*
X347835Y973807D01*
X347759Y974168D01*
X347529Y974478D01*
X347184Y974633D01*
X346800D01*
X346570Y974737D01*
X346379Y974995D01*
X346302Y975357D01*
X346417Y975718D01*
X346685Y975977D01*
X346992Y976080D01*
X347299Y975977D01*
X347567Y975718D01*
X347682Y975357D01*
X347605Y974995D01*
X347414Y974737D01*
X347184Y974633D01*
X346800D01*
X346455Y974478D01*
X346225Y974168D01*
X346149Y973807D01*
X346225Y973445D01*
X346417Y973187D01*
X346724Y973032D01*
X346992Y972980D01*
G01X358600Y1046029D02*
X358907Y1045771D01*
X359252Y1045616D01*
X359558D01*
X359865Y1045771D01*
X360095Y1046029D01*
X360210Y1046391D01*
X360133Y1046753D01*
X359942Y1047063D01*
X359597Y1047269D01*
X359137Y1047373D01*
X358868Y1047579D01*
X358753Y1047941D01*
X358830Y1048303D01*
X359022Y1048561D01*
X359290Y1048716D01*
X359558D01*
X359827Y1048613D01*
X360057Y1048354D01*
G01X362428Y1045616D02*
X362505Y1046288D01*
X362620Y1046856D01*
X362773Y1047373D01*
X362965Y1047941D01*
X363272Y1048716D01*
X361738D01*
G01X359689Y1105185D02*
X359996Y1104927D01*
X360341Y1104772D01*
X360647D01*
X360954Y1104927D01*
X361184Y1105185D01*
X361299Y1105547D01*
X361222Y1105909D01*
X361031Y1106219D01*
X360686Y1106425D01*
X360226Y1106529D01*
X359957Y1106735D01*
X359842Y1107097D01*
X359919Y1107459D01*
X360111Y1107717D01*
X360379Y1107872D01*
X360647D01*
X360916Y1107769D01*
X361146Y1107510D01*
G01X362866Y1106064D02*
X363134Y1106425D01*
X363364Y1106632D01*
X363671Y1106735D01*
X363939Y1106632D01*
X364131Y1106425D01*
X364284Y1106115D01*
X364322Y1105754D01*
X364284Y1105444D01*
X364131Y1105134D01*
X363901Y1104875D01*
X363632Y1104772D01*
X363326Y1104875D01*
X363057Y1105185D01*
X362904Y1105650D01*
X362866Y1106167D01*
X362942Y1106839D01*
X363057Y1107200D01*
X363249Y1107562D01*
X363517Y1107820D01*
X363786Y1107872D01*
X364054Y1107769D01*
X364246Y1107510D01*
G01X378842Y1128779D02*
G03I-19000J0D01*
G01X339987Y1147979D02*
Y1151079D01*
G01X341597D02*
Y1147979D01*
G01Y1149529D02*
X339987D01*
G01X343164Y1150562D02*
X343394Y1150872D01*
X343662Y1151027D01*
X343969Y1151079D01*
X344352Y1150976D01*
X344620Y1150717D01*
X344697Y1150407D01*
X344659Y1150097D01*
X344505Y1149839D01*
X343739Y1149322D01*
X343394Y1148961D01*
X343164Y1148444D01*
X343087Y1147979D01*
X344697D01*
G01X346992D02*
Y1151079D01*
X346532Y1150459D01*
G01Y1147979D02*
X347452D01*
G01X359655Y1221271D02*
X359962Y1221013D01*
X360307Y1220858D01*
X360613D01*
X360920Y1221013D01*
X361150Y1221271D01*
X361265Y1221633D01*
X361188Y1221995D01*
X360997Y1222305D01*
X360652Y1222511D01*
X360192Y1222615D01*
X359923Y1222821D01*
X359808Y1223183D01*
X359885Y1223545D01*
X360077Y1223803D01*
X360345Y1223958D01*
X360613D01*
X360882Y1223855D01*
X361112Y1223596D01*
G01X363483Y1220858D02*
X363560Y1221530D01*
X363675Y1222098D01*
X363828Y1222615D01*
X364020Y1223183D01*
X364327Y1223958D01*
X362793D01*
G01X359439Y1280603D02*
X359746Y1280345D01*
X360091Y1280190D01*
X360397D01*
X360704Y1280345D01*
X360934Y1280603D01*
X361049Y1280965D01*
X360972Y1281327D01*
X360781Y1281637D01*
X360436Y1281843D01*
X359976Y1281947D01*
X359707Y1282153D01*
X359592Y1282515D01*
X359669Y1282877D01*
X359861Y1283135D01*
X360129Y1283290D01*
X360397D01*
X360666Y1283187D01*
X360896Y1282928D01*
G01X362616Y1281482D02*
X362884Y1281843D01*
X363114Y1282050D01*
X363421Y1282153D01*
X363689Y1282050D01*
X363881Y1281843D01*
X364034Y1281533D01*
X364072Y1281172D01*
X364034Y1280862D01*
X363881Y1280552D01*
X363651Y1280293D01*
X363382Y1280190D01*
X363076Y1280293D01*
X362807Y1280603D01*
X362654Y1281068D01*
X362616Y1281585D01*
X362692Y1282257D01*
X362807Y1282618D01*
X362999Y1282980D01*
X363267Y1283238D01*
X363536Y1283290D01*
X363804Y1283187D01*
X363996Y1282928D01*
G01X378842Y1303780D02*
G03I-19000J0D01*
G01X339987Y1322980D02*
Y1326080D01*
G01X341597D02*
Y1322980D01*
G01Y1324530D02*
X339987D01*
G01X343164Y1325563D02*
X343394Y1325873D01*
X343662Y1326028D01*
X343969Y1326080D01*
X344352Y1325977D01*
X344620Y1325718D01*
X344697Y1325408D01*
X344659Y1325098D01*
X344505Y1324840D01*
X343739Y1324323D01*
X343394Y1323962D01*
X343164Y1323445D01*
X343087Y1322980D01*
X344697D01*
G01X346264Y1324272D02*
X346532Y1324633D01*
X346762Y1324840D01*
X347069Y1324943D01*
X347337Y1324840D01*
X347529Y1324633D01*
X347682Y1324323D01*
X347720Y1323962D01*
X347682Y1323652D01*
X347529Y1323342D01*
X347299Y1323083D01*
X347030Y1322980D01*
X346724Y1323083D01*
X346455Y1323393D01*
X346302Y1323858D01*
X346264Y1324375D01*
X346340Y1325047D01*
X346455Y1325408D01*
X346647Y1325770D01*
X346915Y1326028D01*
X347184Y1326080D01*
X347452Y1325977D01*
X347644Y1325718D01*
G01X358296Y1394886D02*
X358603Y1394628D01*
X358948Y1394473D01*
X359254D01*
X359561Y1394628D01*
X359791Y1394886D01*
X359906Y1395248D01*
X359829Y1395610D01*
X359638Y1395920D01*
X359293Y1396126D01*
X358833Y1396230D01*
X358564Y1396436D01*
X358449Y1396798D01*
X358526Y1397160D01*
X358718Y1397418D01*
X358986Y1397573D01*
X359254D01*
X359523Y1397470D01*
X359753Y1397211D01*
G01X362124Y1394473D02*
X362201Y1395145D01*
X362316Y1395713D01*
X362469Y1396230D01*
X362661Y1396798D01*
X362968Y1397573D01*
X361434D01*
G01X359626Y1455377D02*
X359933Y1455119D01*
X360278Y1454964D01*
X360584D01*
X360891Y1455119D01*
X361121Y1455377D01*
X361236Y1455739D01*
X361159Y1456101D01*
X360968Y1456411D01*
X360623Y1456617D01*
X360163Y1456721D01*
X359894Y1456927D01*
X359779Y1457289D01*
X359856Y1457651D01*
X360048Y1457909D01*
X360316Y1458064D01*
X360584D01*
X360853Y1457961D01*
X361083Y1457702D01*
G01X362803Y1456256D02*
X363071Y1456617D01*
X363301Y1456824D01*
X363608Y1456927D01*
X363876Y1456824D01*
X364068Y1456617D01*
X364221Y1456307D01*
X364259Y1455946D01*
X364221Y1455636D01*
X364068Y1455326D01*
X363838Y1455067D01*
X363569Y1454964D01*
X363263Y1455067D01*
X362994Y1455377D01*
X362841Y1455842D01*
X362803Y1456359D01*
X362879Y1457031D01*
X362994Y1457392D01*
X363186Y1457754D01*
X363454Y1458012D01*
X363723Y1458064D01*
X363991Y1457961D01*
X364183Y1457702D01*
G01X378842Y1478780D02*
G03I-19000J0D01*
G01X339987Y1497980D02*
Y1501080D01*
G01X341597D02*
Y1497980D01*
G01Y1499530D02*
X339987D01*
G01X343164Y1500563D02*
X343394Y1500873D01*
X343662Y1501028D01*
X343969Y1501080D01*
X344352Y1500977D01*
X344620Y1500718D01*
X344697Y1500408D01*
X344659Y1500098D01*
X344505Y1499840D01*
X343739Y1499323D01*
X343394Y1498962D01*
X343164Y1498445D01*
X343087Y1497980D01*
X344697D01*
G01X346149Y1498600D02*
X346379Y1498238D01*
X346685Y1498032D01*
X347030Y1497980D01*
X347337Y1498032D01*
X347644Y1498290D01*
X347835Y1498600D01*
X347874Y1498910D01*
X347797Y1499272D01*
X347529Y1499530D01*
X347260Y1499633D01*
X346915D01*
G01X347260D02*
X347490Y1499788D01*
X347682Y1500047D01*
X347759Y1500357D01*
X347682Y1500667D01*
X347490Y1500925D01*
X347145Y1501080D01*
X346800Y1501028D01*
X346455Y1500822D01*
G01X361441Y1560664D02*
X361748Y1560406D01*
X362093Y1560251D01*
X362399D01*
X362706Y1560406D01*
X362936Y1560664D01*
X363051Y1561026D01*
X362974Y1561388D01*
X362783Y1561698D01*
X362438Y1561904D01*
X361978Y1562008D01*
X361709Y1562214D01*
X361594Y1562576D01*
X361671Y1562938D01*
X361863Y1563196D01*
X362131Y1563351D01*
X362399D01*
X362668Y1563248D01*
X362898Y1562989D01*
G01X365269Y1560251D02*
X365346Y1560923D01*
X365461Y1561491D01*
X365614Y1562008D01*
X365806Y1562576D01*
X366113Y1563351D01*
X364579D01*
G01X358139Y1630279D02*
X358446Y1630021D01*
X358791Y1629866D01*
X359097D01*
X359404Y1630021D01*
X359634Y1630279D01*
X359749Y1630641D01*
X359672Y1631003D01*
X359481Y1631313D01*
X359136Y1631519D01*
X358676Y1631623D01*
X358407Y1631829D01*
X358292Y1632191D01*
X358369Y1632553D01*
X358561Y1632811D01*
X358829Y1632966D01*
X359097D01*
X359366Y1632863D01*
X359596Y1632604D01*
G01X361316Y1631158D02*
X361584Y1631519D01*
X361814Y1631726D01*
X362121Y1631829D01*
X362389Y1631726D01*
X362581Y1631519D01*
X362734Y1631209D01*
X362772Y1630848D01*
X362734Y1630538D01*
X362581Y1630228D01*
X362351Y1629969D01*
X362082Y1629866D01*
X361776Y1629969D01*
X361507Y1630279D01*
X361354Y1630744D01*
X361316Y1631261D01*
X361392Y1631933D01*
X361507Y1632294D01*
X361699Y1632656D01*
X361967Y1632914D01*
X362236Y1632966D01*
X362504Y1632863D01*
X362696Y1632604D01*
G01X378842Y1653780D02*
G03I-19000J0D01*
G01X339987Y1672980D02*
Y1676080D01*
G01X341597D02*
Y1672980D01*
G01Y1674530D02*
X339987D01*
G01X343892Y1672980D02*
Y1676080D01*
X343432Y1675460D01*
G01Y1672980D02*
X344352D01*
G01X346149Y1673445D02*
X346379Y1673187D01*
X346647Y1673032D01*
X346992Y1672980D01*
X347337Y1673083D01*
X347605Y1673290D01*
X347797Y1673652D01*
X347835Y1674065D01*
X347759Y1674478D01*
X347567Y1674737D01*
X347299Y1674943D01*
X347030Y1674995D01*
X346762Y1674943D01*
X346417Y1674737D01*
X346532Y1676080D01*
X347567D01*
G01X358334Y1744266D02*
X358641Y1744008D01*
X358986Y1743853D01*
X359292D01*
X359599Y1744008D01*
X359829Y1744266D01*
X359944Y1744628D01*
X359867Y1744990D01*
X359676Y1745300D01*
X359331Y1745506D01*
X358871Y1745610D01*
X358602Y1745816D01*
X358487Y1746178D01*
X358564Y1746540D01*
X358756Y1746798D01*
X359024Y1746953D01*
X359292D01*
X359561Y1746850D01*
X359791Y1746591D01*
G01X362162Y1743853D02*
X362239Y1744525D01*
X362354Y1745093D01*
X362507Y1745610D01*
X362699Y1746178D01*
X363006Y1746953D01*
X361472D01*
G01X340093Y1807568D02*
X340400Y1807310D01*
X340745Y1807155D01*
X341051D01*
X341358Y1807310D01*
X341588Y1807568D01*
X341703Y1807930D01*
X341626Y1808292D01*
X341435Y1808602D01*
X341090Y1808808D01*
X340630Y1808912D01*
X340361Y1809118D01*
X340246Y1809480D01*
X340323Y1809842D01*
X340515Y1810100D01*
X340783Y1810255D01*
X341051D01*
X341320Y1810152D01*
X341550Y1809893D01*
G01X343998Y1807155D02*
Y1810255D01*
X343538Y1809635D01*
G01Y1807155D02*
X344458D01*
G01X361027Y1805547D02*
X361334Y1805289D01*
X361679Y1805134D01*
X361985D01*
X362292Y1805289D01*
X362522Y1805547D01*
X362637Y1805909D01*
X362560Y1806271D01*
X362369Y1806581D01*
X362024Y1806787D01*
X361564Y1806891D01*
X361295Y1807097D01*
X361180Y1807459D01*
X361257Y1807821D01*
X361449Y1808079D01*
X361717Y1808234D01*
X361985D01*
X362254Y1808131D01*
X362484Y1807872D01*
G01X364204Y1806426D02*
X364472Y1806787D01*
X364702Y1806994D01*
X365009Y1807097D01*
X365277Y1806994D01*
X365469Y1806787D01*
X365622Y1806477D01*
X365660Y1806116D01*
X365622Y1805806D01*
X365469Y1805496D01*
X365239Y1805237D01*
X364970Y1805134D01*
X364664Y1805237D01*
X364395Y1805547D01*
X364242Y1806012D01*
X364204Y1806529D01*
X364280Y1807201D01*
X364395Y1807562D01*
X364587Y1807924D01*
X364855Y1808182D01*
X365124Y1808234D01*
X365392Y1808131D01*
X365584Y1807872D01*
G01X378842Y1828779D02*
G03I-19000J0D01*
G01X339987Y1847979D02*
Y1851079D01*
G01X341597D02*
Y1847979D01*
G01Y1849529D02*
X339987D01*
G01X343892Y1847979D02*
Y1851079D01*
X343432Y1850459D01*
G01Y1847979D02*
X344352D01*
G01X346340Y1848341D02*
X346609Y1848082D01*
X346915Y1847979D01*
X347222Y1848082D01*
X347490Y1848392D01*
X347682Y1848857D01*
X347759Y1849322D01*
Y1849891D01*
X347682Y1850356D01*
X347490Y1850769D01*
X347260Y1850976D01*
X346992Y1851079D01*
X346685Y1850976D01*
X346455Y1850769D01*
X346302Y1850459D01*
X346225Y1850046D01*
X346302Y1849684D01*
X346494Y1849322D01*
X346724Y1849116D01*
X346992Y1849064D01*
X347299Y1849167D01*
X347529Y1849426D01*
X347759Y1849891D01*
G01X341028Y1981458D02*
X341335Y1981200D01*
X341680Y1981045D01*
X341986D01*
X342293Y1981200D01*
X342523Y1981458D01*
X342638Y1981820D01*
X342561Y1982182D01*
X342370Y1982492D01*
X342025Y1982698D01*
X341565Y1982802D01*
X341296Y1983008D01*
X341181Y1983370D01*
X341258Y1983732D01*
X341450Y1983990D01*
X341718Y1984145D01*
X341986D01*
X342255Y1984042D01*
X342485Y1983783D01*
G01X344933Y1981045D02*
Y1984145D01*
X344473Y1983525D01*
G01Y1981045D02*
X345393D01*
G01X378842Y2003780D02*
G03I-19000J0D01*
G01X339987Y2022980D02*
Y2026080D01*
G01X341597D02*
Y2022980D01*
G01Y2024530D02*
X339987D01*
G01X343164Y2025563D02*
X343394Y2025873D01*
X343662Y2026028D01*
X343969Y2026080D01*
X344352Y2025977D01*
X344620Y2025718D01*
X344697Y2025408D01*
X344659Y2025098D01*
X344505Y2024840D01*
X343739Y2024323D01*
X343394Y2023962D01*
X343164Y2023445D01*
X343087Y2022980D01*
X344697D01*
G01X347452D02*
Y2026080D01*
X346034Y2023858D01*
X347950D01*
G01X367867Y695209D02*
X368174Y694951D01*
X368519Y694796D01*
X368825D01*
X369132Y694951D01*
X369362Y695209D01*
X369477Y695571D01*
X369400Y695933D01*
X369209Y696243D01*
X368864Y696449D01*
X368404Y696553D01*
X368135Y696759D01*
X368020Y697121D01*
X368097Y697483D01*
X368289Y697741D01*
X368557Y697896D01*
X368825D01*
X369094Y697793D01*
X369324Y697534D01*
G01X371695Y694796D02*
X371772Y695468D01*
X371887Y696036D01*
X372040Y696553D01*
X372232Y697121D01*
X372539Y697896D01*
X371005D01*
G01X364173Y1917622D02*
X364480Y1917364D01*
X364825Y1917209D01*
X365131D01*
X365438Y1917364D01*
X365668Y1917622D01*
X365783Y1917984D01*
X365706Y1918346D01*
X365515Y1918656D01*
X365170Y1918862D01*
X364710Y1918966D01*
X364441Y1919172D01*
X364326Y1919534D01*
X364403Y1919896D01*
X364595Y1920154D01*
X364863Y1920309D01*
X365131D01*
X365400Y1920206D01*
X365630Y1919947D01*
G01X368001Y1917209D02*
X368078Y1917881D01*
X368193Y1918449D01*
X368346Y1918966D01*
X368538Y1919534D01*
X368845Y1920309D01*
X367311D01*
G01X371157Y1981062D02*
X371464Y1980804D01*
X371809Y1980649D01*
X372115D01*
X372422Y1980804D01*
X372652Y1981062D01*
X372767Y1981424D01*
X372690Y1981786D01*
X372499Y1982096D01*
X372154Y1982302D01*
X371694Y1982406D01*
X371425Y1982612D01*
X371310Y1982974D01*
X371387Y1983336D01*
X371579Y1983594D01*
X371847Y1983749D01*
X372115D01*
X372384Y1983646D01*
X372614Y1983387D01*
G01X374334Y1981941D02*
X374602Y1982302D01*
X374832Y1982509D01*
X375139Y1982612D01*
X375407Y1982509D01*
X375599Y1982302D01*
X375752Y1981992D01*
X375790Y1981631D01*
X375752Y1981321D01*
X375599Y1981011D01*
X375369Y1980752D01*
X375100Y1980649D01*
X374794Y1980752D01*
X374525Y1981062D01*
X374372Y1981527D01*
X374334Y1982044D01*
X374410Y1982716D01*
X374525Y1983077D01*
X374717Y1983439D01*
X374985Y1983697D01*
X375254Y1983749D01*
X375522Y1983646D01*
X375714Y1983387D01*
G01X418149Y1122D02*
Y53288D01*
G01Y176122D02*
Y228288D01*
G01Y351122D02*
Y403288D01*
G01X418150Y526122D02*
Y578288D01*
G01Y701122D02*
Y753288D01*
G01X418149Y876122D02*
Y928288D01*
G01Y1051122D02*
Y1103288D01*
G01Y1226122D02*
Y1278288D01*
G01Y1401122D02*
Y1453288D01*
G01Y1576122D02*
Y1628288D01*
G01Y1751122D02*
Y1803288D01*
G01Y1926122D02*
Y1978288D01*
G01X443000Y-130000D02*
X445500Y-122000D01*
X448000Y-130000D01*
G01X447100Y-127200D02*
X443900D01*
G01X473000Y-130000D02*
Y-122000D01*
X471800Y-123600D01*
G01Y-130000D02*
X474200D01*
G01X479100Y-126667D02*
X479800Y-125733D01*
X480400Y-125200D01*
X481200Y-124933D01*
X481900Y-125200D01*
X482400Y-125733D01*
X482800Y-126533D01*
X482900Y-127467D01*
X482800Y-128267D01*
X482400Y-129067D01*
X481800Y-129733D01*
X481100Y-130000D01*
X480300Y-129733D01*
X479600Y-128934D01*
X479200Y-127733D01*
X479100Y-126400D01*
X479300Y-124667D01*
X479600Y-123733D01*
X480100Y-122800D01*
X480800Y-122133D01*
X481500Y-122000D01*
X482200Y-122267D01*
X482700Y-122933D01*
G54D12*
G01X73363Y1667658D02*
Y1669418D01*
G01X73203Y1667658D02*
Y1669418D01*
G01X73043Y1667658D02*
Y1669418D01*
G01X72883Y1667658D02*
Y1669418D01*
G01X72723Y1667658D02*
Y1669418D01*
G01X72563Y1667658D02*
Y1669418D01*
G01X72403Y1667658D02*
Y1669418D01*
G01X72243Y1667658D02*
Y1669418D01*
G01X72083Y1667658D02*
Y1669418D01*
G01X71923Y1667658D02*
Y1669418D01*
G01X71763Y1667658D02*
Y1669418D01*
G01X71603Y1667658D02*
Y1669418D01*
G01X71443Y1667658D02*
Y1669418D01*
G01X71283Y1667658D02*
Y1669418D01*
G01X71123Y1667658D02*
Y1669418D01*
G01X70963Y1667658D02*
Y1669418D01*
G01X70803Y1667658D02*
Y1669258D01*
G01X70643Y1667658D02*
Y1669258D01*
G01X70483Y1667658D02*
Y1669258D01*
G01X70323Y1667658D02*
Y1671018D01*
G01X70163Y1667658D02*
Y1671018D01*
G01X70003Y1667658D02*
Y1670858D01*
G01X69843Y1667658D02*
Y1670858D01*
G01X69683Y1667658D02*
Y1670698D01*
G01X69523Y1667658D02*
Y1670698D01*
G01X69363Y1667658D02*
Y1670698D01*
G01X69203Y1667658D02*
Y1670538D01*
G01X69043Y1667658D02*
Y1670538D01*
G01X68883Y1667658D02*
Y1670378D01*
G01X68723Y1667658D02*
Y1670378D01*
G01X68563Y1667658D02*
Y1670378D01*
G01X68403Y1667658D02*
Y1670218D01*
G01X73363Y1670538D02*
Y1672138D01*
G01X73203Y1670538D02*
Y1672138D01*
G01X73043Y1670378D02*
Y1672138D01*
G01X72883Y1670378D02*
Y1671978D01*
G01X72723Y1670218D02*
Y1671978D01*
G01X72563Y1670218D02*
Y1671978D01*
G01X72403Y1670218D02*
Y1671818D01*
G01X72243Y1670058D02*
Y1671818D01*
G01X72083Y1670058D02*
Y1671658D01*
G01X71923Y1669898D02*
Y1671658D01*
G01X71763Y1669898D02*
Y1671658D01*
G01X71603Y1669898D02*
Y1671498D01*
G01X71443Y1669738D02*
Y1671498D01*
G01X71283Y1669738D02*
Y1671338D01*
G01X71123Y1669578D02*
Y1671338D01*
G01X70963Y1669578D02*
Y1671338D01*
G01X70803Y1669578D02*
Y1671178D01*
G01X70643Y1669418D02*
Y1671178D01*
G01X70483Y1669418D02*
Y1671018D01*
G01X73363Y1692938D02*
Y1695338D01*
G01Y1685738D02*
Y1687818D01*
G01Y1681738D02*
Y1683498D01*
G01Y1677578D02*
Y1679338D01*
G01Y1674858D02*
Y1676298D01*
G01X73203Y1692938D02*
Y1695498D01*
G01Y1685738D02*
Y1687978D01*
G01Y1681738D02*
Y1683498D01*
G01Y1677578D02*
Y1679338D01*
G01Y1674858D02*
Y1676458D01*
G01X73043Y1692938D02*
Y1695658D01*
G01Y1690858D02*
Y1691178D01*
G01Y1685898D02*
Y1688138D01*
G01Y1681738D02*
Y1683498D01*
G01Y1677578D02*
Y1679338D01*
G01Y1675018D02*
Y1676458D01*
G01X72883Y1697098D02*
Y1697418D01*
G01Y1692938D02*
Y1695978D01*
G01Y1690698D02*
Y1691178D01*
G01Y1685898D02*
Y1688458D01*
G01Y1681738D02*
Y1683498D01*
G01Y1677578D02*
Y1679338D01*
G01Y1675018D02*
Y1676618D01*
G01X72723Y1694858D02*
Y1697418D01*
G01Y1692938D02*
Y1694698D01*
G01Y1690218D02*
Y1691178D01*
G01Y1686058D02*
Y1688778D01*
G01Y1681738D02*
Y1683498D01*
G01Y1677578D02*
Y1679338D01*
G01Y1675018D02*
Y1676618D01*
G01X72563Y1694858D02*
Y1697418D01*
G01Y1692938D02*
Y1694698D01*
G01Y1686218D02*
Y1691178D01*
G01Y1681738D02*
Y1683498D01*
G01Y1677578D02*
Y1679338D01*
G01Y1675178D02*
Y1676618D01*
G01X72403Y1695018D02*
Y1697418D01*
G01Y1692938D02*
Y1694698D01*
G01Y1686378D02*
Y1691178D01*
G01Y1681738D02*
Y1683498D01*
G01Y1677578D02*
Y1679338D01*
G01Y1675178D02*
Y1676778D01*
G01X72243Y1695018D02*
Y1697418D01*
G01Y1692938D02*
Y1694698D01*
G01Y1686538D02*
Y1691178D01*
G01Y1681738D02*
Y1683498D01*
G01Y1677578D02*
Y1679338D01*
G01Y1675338D02*
Y1676778D01*
G01X72083Y1695178D02*
Y1697418D01*
G01Y1692938D02*
Y1694698D01*
G01Y1686698D02*
Y1691178D01*
G01Y1681738D02*
Y1683498D01*
G01Y1677578D02*
Y1679338D01*
G01Y1675338D02*
Y1676938D01*
G01X71923Y1695338D02*
Y1697418D01*
G01Y1692938D02*
Y1694698D01*
G01Y1686858D02*
Y1691178D01*
G01Y1681738D02*
Y1683498D01*
G01Y1677578D02*
Y1679338D01*
G01Y1675498D02*
Y1676938D01*
G01X71763Y1695498D02*
Y1697418D01*
G01Y1692938D02*
Y1694698D01*
G01Y1687178D02*
Y1691178D01*
G01Y1681738D02*
Y1683498D01*
G01Y1677578D02*
Y1679338D01*
G01Y1675498D02*
Y1676938D01*
G01X71603Y1695658D02*
Y1697418D01*
G01Y1692938D02*
Y1694698D01*
G01Y1687498D02*
Y1691178D01*
G01Y1681738D02*
Y1683498D01*
G01Y1677578D02*
Y1679338D01*
G01Y1675498D02*
Y1677098D01*
G01X71443Y1695818D02*
Y1697418D01*
G01Y1692938D02*
Y1694698D01*
G01Y1687818D02*
Y1690858D01*
G01Y1681738D02*
Y1683498D01*
G01Y1677578D02*
Y1679338D01*
G01Y1675658D02*
Y1677098D01*
G01X71283Y1696298D02*
Y1697258D01*
G01Y1688458D02*
Y1690218D01*
G01Y1677578D02*
Y1679338D01*
G01Y1675658D02*
Y1677258D01*
G01X71123Y1677578D02*
Y1679338D01*
G01Y1675818D02*
Y1677258D01*
G01X70963Y1677578D02*
Y1679338D01*
G01Y1675818D02*
Y1677258D01*
G01X70803Y1677578D02*
Y1679338D01*
G01Y1675818D02*
Y1677418D01*
G01X70643Y1677578D02*
Y1679338D01*
G01Y1675978D02*
Y1677418D01*
G01X70483Y1677578D02*
Y1679338D01*
G01Y1675978D02*
Y1677418D01*
G01X70323Y1676138D02*
Y1679338D01*
G01X70163Y1676138D02*
Y1679338D01*
G01X70003Y1676138D02*
Y1679338D01*
G01X69843Y1676298D02*
Y1679338D01*
G01X69683Y1682218D02*
Y1683018D01*
G01Y1676298D02*
Y1679338D01*
G01X69523Y1681898D02*
Y1683338D01*
G01Y1676458D02*
Y1679338D01*
G01X69363Y1681738D02*
Y1683498D01*
G01Y1676458D02*
Y1679338D01*
G01X69203Y1681738D02*
Y1683498D01*
G01Y1676458D02*
Y1679338D01*
G01X69043Y1681578D02*
Y1683658D01*
G01Y1676618D02*
Y1679338D01*
G01X68883Y1681578D02*
Y1683658D01*
G01Y1676618D02*
Y1679338D01*
G01X68723Y1681578D02*
Y1683658D01*
G01Y1676778D02*
Y1679338D01*
G01X68563Y1681578D02*
Y1683658D01*
G01Y1676778D02*
Y1679338D01*
G01X68403Y1681738D02*
Y1683498D01*
G01Y1676778D02*
Y1679338D01*
G01X68243Y1681738D02*
Y1683498D01*
G01X68083Y1681898D02*
Y1683338D01*
G01X67923Y1682218D02*
Y1683018D01*
G01X73363Y1698538D02*
Y1700618D01*
G01Y1719498D02*
Y1721418D01*
G01Y1714218D02*
Y1716298D01*
G01Y1707338D02*
Y1709098D01*
G01Y1703818D02*
Y1705738D01*
G01X73203Y1719338D02*
Y1721418D01*
G01Y1714378D02*
Y1716298D01*
G01Y1707338D02*
Y1709098D01*
G01Y1703658D02*
Y1705738D01*
G01Y1698698D02*
Y1700618D01*
G01X73043Y1719178D02*
Y1721258D01*
G01Y1714378D02*
Y1716618D01*
G01Y1707338D02*
Y1709258D01*
G01Y1703498D02*
Y1705578D01*
G01Y1698698D02*
Y1700938D01*
G01X72883Y1718858D02*
Y1721258D01*
G01Y1714538D02*
Y1716778D01*
G01Y1711818D02*
Y1712298D01*
G01Y1707498D02*
Y1709418D01*
G01Y1703178D02*
Y1705578D01*
G01Y1698858D02*
Y1701098D01*
G01X72723Y1722698D02*
Y1727998D01*
G01Y1718538D02*
Y1721098D01*
G01Y1714698D02*
Y1717258D01*
G01Y1711338D02*
Y1712298D01*
G01Y1707498D02*
Y1709738D01*
G01Y1702858D02*
Y1705418D01*
G01Y1699018D02*
Y1701578D01*
G01X72563Y1722698D02*
Y1727998D01*
G01Y1714698D02*
Y1720938D01*
G01Y1707658D02*
Y1712298D01*
G01Y1699018D02*
Y1705258D01*
G01X72403Y1722698D02*
Y1727998D01*
G01Y1714858D02*
Y1720938D01*
G01Y1707658D02*
Y1712298D01*
G01Y1699178D02*
Y1705258D01*
G01X72243Y1722698D02*
Y1727998D01*
G01Y1715018D02*
Y1720778D01*
G01Y1707818D02*
Y1712298D01*
G01Y1699338D02*
Y1705098D01*
G01X72083Y1722698D02*
Y1727498D01*
G01Y1715178D02*
Y1720618D01*
G01Y1707978D02*
Y1712298D01*
G01Y1699498D02*
Y1704938D01*
G01X71923Y1722698D02*
Y1727998D01*
G01Y1715498D02*
Y1720298D01*
G01Y1708138D02*
Y1712298D01*
G01Y1699818D02*
Y1704618D01*
G01X71763Y1722698D02*
Y1727498D01*
G01Y1715658D02*
Y1720138D01*
G01Y1708298D02*
Y1712298D01*
G01Y1699978D02*
Y1704458D01*
G01X71603Y1722698D02*
Y1727998D01*
G01Y1715978D02*
Y1719818D01*
G01Y1708618D02*
Y1712298D01*
G01Y1700298D02*
Y1704138D01*
G01X71443Y1722698D02*
Y1727998D01*
G01Y1716458D02*
Y1719498D01*
G01Y1709098D02*
Y1712138D01*
G01Y1700778D02*
Y1703818D01*
G01X71283Y1717098D02*
Y1718858D01*
G01Y1709578D02*
Y1711498D01*
G01Y1701418D02*
Y1703178D01*
G01X73363Y1724138D02*
Y1725738D01*
G01X73203Y1724138D02*
Y1725738D01*
G01X73043Y1724138D02*
Y1725738D01*
G01X72883Y1724138D02*
Y1725738D01*
G01X72723Y1727978D02*
Y1732778D01*
G01X72563Y1727978D02*
Y1732778D01*
G01X72403Y1727978D02*
Y1732778D01*
G01X72243Y1727978D02*
Y1732778D01*
G01X72083Y1727978D02*
Y1732778D01*
G01X71923Y1727978D02*
Y1732778D01*
G01X71763Y1727978D02*
Y1732778D01*
G01X71603Y1727978D02*
Y1732778D01*
G01X71443Y1727978D02*
Y1732778D01*
G01X71283Y1724138D02*
Y1725738D01*
G01X71123Y1724138D02*
Y1725738D01*
G01X70963Y1724138D02*
Y1725738D01*
G01X70803Y1724138D02*
Y1725738D01*
G01X70643Y1724138D02*
Y1725738D01*
G01X70483Y1724138D02*
Y1725738D01*
G01X70323Y1724138D02*
Y1725738D01*
G01X70163Y1724138D02*
Y1725738D01*
G01X70003Y1724138D02*
Y1725738D01*
G01X69843Y1724138D02*
Y1725898D01*
G01X69683Y1724138D02*
Y1725898D01*
G01X69523Y1724138D02*
Y1725898D01*
G01X69363Y1724138D02*
Y1726058D01*
G01X69203Y1724138D02*
Y1726218D01*
G01X69043Y1727658D02*
Y1727818D01*
G01Y1724298D02*
Y1726538D01*
G01X68883Y1724298D02*
Y1727818D01*
G01X68723Y1724458D02*
Y1727818D01*
G01X68563Y1724618D02*
Y1727818D01*
G01X68403Y1724618D02*
Y1727818D01*
G01X68243Y1724778D02*
Y1727818D01*
G01X68083Y1725098D02*
Y1727818D01*
G01X67923Y1725258D02*
Y1727818D01*
G01X67763Y1725578D02*
Y1727818D01*
G01X67603Y1726058D02*
Y1727658D01*
G01X73363Y1729258D02*
Y1731018D01*
G01X73203Y1729258D02*
Y1731018D01*
G01X73043Y1729258D02*
Y1731018D01*
G01X72883Y1729258D02*
Y1731018D01*
G01X71283Y1729258D02*
Y1731018D01*
G01X71123Y1729258D02*
Y1731018D01*
G01X70963Y1729258D02*
Y1731018D01*
G01X70803Y1729258D02*
Y1731018D01*
G01X70643Y1729258D02*
Y1731018D01*
G01X70483Y1729258D02*
Y1731018D01*
G01X70323Y1729258D02*
Y1731018D01*
G01X70163Y1729258D02*
Y1731018D01*
G01X70003Y1729258D02*
Y1731018D01*
G01X69843Y1729258D02*
Y1731018D01*
G01X69683Y1729258D02*
Y1731018D01*
G01X69523Y1729578D02*
Y1731018D01*
G01X69363Y1730218D02*
Y1731018D01*
G01X69203Y1730698D02*
Y1731018D01*
G01X78963Y1667658D02*
Y1669418D01*
G01X78803Y1667658D02*
Y1669418D01*
G01X78643Y1667658D02*
Y1669418D01*
G01X78483Y1667658D02*
Y1669418D01*
G01X78323Y1667658D02*
Y1669418D01*
G01X78163Y1667658D02*
Y1669418D01*
G01X78003Y1667658D02*
Y1669418D01*
G01X77843Y1667658D02*
Y1669418D01*
G01X77683Y1667658D02*
Y1669418D01*
G01X77523Y1667658D02*
Y1669418D01*
G01X77363Y1667658D02*
Y1669418D01*
G01X77203Y1667658D02*
Y1669418D01*
G01X77043Y1667658D02*
Y1669418D01*
G01X76883Y1667658D02*
Y1669418D01*
G01X76723Y1667658D02*
Y1669418D01*
G01X76563Y1667658D02*
Y1669418D01*
G01X76403Y1667658D02*
Y1669418D01*
G01X76243Y1667658D02*
Y1669418D01*
G01X76083Y1667658D02*
Y1669418D01*
G01X75923Y1667658D02*
Y1669418D01*
G01X75763Y1667658D02*
Y1669418D01*
G01X75603Y1667658D02*
Y1669418D01*
G01X75443Y1667658D02*
Y1669418D01*
G01X75283Y1667658D02*
Y1669418D01*
G01X75123Y1667658D02*
Y1669418D01*
G01X74963Y1667658D02*
Y1669418D01*
G01X74803Y1667658D02*
Y1669418D01*
G01X74643Y1667658D02*
Y1669418D01*
G01X74483Y1667658D02*
Y1669418D01*
G01X74323Y1667658D02*
Y1669418D01*
G01X74163Y1667658D02*
Y1669418D01*
G01X74003Y1667658D02*
Y1669418D01*
G01X73843Y1667658D02*
Y1669418D01*
G01X73683Y1667658D02*
Y1669418D01*
G01X73523Y1667658D02*
Y1669418D01*
G01X78963Y1672778D02*
Y1674058D01*
G01X78803Y1672778D02*
Y1674218D01*
G01X78643Y1672778D02*
Y1674218D01*
G01X78483Y1672618D02*
Y1674218D01*
G01X78323Y1672618D02*
Y1674378D01*
G01X78163Y1672458D02*
Y1674378D01*
G01X78003Y1672458D02*
Y1674538D01*
G01X77843Y1672298D02*
Y1674538D01*
G01X77683Y1672298D02*
Y1674538D01*
G01X77523Y1672298D02*
Y1674698D01*
G01X77363Y1672138D02*
Y1674698D01*
G01X77203Y1672138D02*
Y1674858D01*
G01X77043Y1671978D02*
Y1674858D01*
G01X76883Y1671978D02*
Y1674858D01*
G01X76723Y1671978D02*
Y1675018D01*
G01X76563Y1673578D02*
Y1675018D01*
G01Y1671818D02*
Y1673418D01*
G01X76403Y1673578D02*
Y1675178D01*
G01Y1671818D02*
Y1673418D01*
G01X76243Y1673738D02*
Y1675178D01*
G01Y1671658D02*
Y1673418D01*
G01X76083Y1673738D02*
Y1675338D01*
G01Y1671658D02*
Y1673258D01*
G01X75923Y1673738D02*
Y1675338D01*
G01Y1671658D02*
Y1673258D01*
G01X75763Y1673898D02*
Y1675338D01*
G01Y1671498D02*
Y1673098D01*
G01X75603Y1673898D02*
Y1675498D01*
G01Y1671498D02*
Y1673098D01*
G01X75443Y1674058D02*
Y1675498D01*
G01Y1671338D02*
Y1673098D01*
G01X75283Y1674058D02*
Y1675658D01*
G01Y1671338D02*
Y1672938D01*
G01X75123Y1674058D02*
Y1675658D01*
G01Y1671338D02*
Y1672938D01*
G01X74963Y1674218D02*
Y1675658D01*
G01Y1671178D02*
Y1672778D01*
G01X74803Y1674218D02*
Y1675818D01*
G01Y1671178D02*
Y1672778D01*
G01X74643Y1674378D02*
Y1675818D01*
G01Y1671018D02*
Y1672778D01*
G01X74483Y1674378D02*
Y1675978D01*
G01Y1671018D02*
Y1672618D01*
G01X74323Y1674378D02*
Y1675978D01*
G01Y1671018D02*
Y1672618D01*
G01X74163Y1670858D02*
Y1672458D01*
G01X74003Y1670858D02*
Y1672458D01*
G01X73843Y1670698D02*
Y1672458D01*
G01X73683Y1670698D02*
Y1672298D01*
G01X73523Y1670698D02*
Y1672298D01*
G01X79123Y1688138D02*
Y1689898D01*
G01X78963Y1692938D02*
Y1694698D01*
G01Y1687658D02*
Y1690538D01*
G01Y1681738D02*
Y1683498D01*
G01Y1677578D02*
Y1679338D01*
G01X78803Y1692938D02*
Y1694698D01*
G01Y1687178D02*
Y1691018D01*
G01Y1681738D02*
Y1683498D01*
G01Y1677578D02*
Y1679338D01*
G01X78643Y1692938D02*
Y1694698D01*
G01Y1687018D02*
Y1691178D01*
G01Y1681738D02*
Y1683498D01*
G01Y1677578D02*
Y1679338D01*
G01X78483Y1692938D02*
Y1694698D01*
G01Y1686698D02*
Y1691178D01*
G01Y1681738D02*
Y1683498D01*
G01Y1677578D02*
Y1679338D01*
G01X78323Y1692938D02*
Y1694698D01*
G01Y1686538D02*
Y1691178D01*
G01Y1681738D02*
Y1683498D01*
G01Y1677578D02*
Y1679338D01*
G01X78163Y1692938D02*
Y1694698D01*
G01Y1686378D02*
Y1691178D01*
G01Y1681738D02*
Y1683498D01*
G01Y1677578D02*
Y1679338D01*
G01X78003Y1692938D02*
Y1694698D01*
G01Y1686218D02*
Y1691178D01*
G01Y1681738D02*
Y1683498D01*
G01Y1677578D02*
Y1679338D01*
G01X77843Y1692938D02*
Y1694698D01*
G01Y1686058D02*
Y1691178D01*
G01Y1681738D02*
Y1683498D01*
G01Y1677578D02*
Y1679338D01*
G01X77683Y1692938D02*
Y1694698D01*
G01Y1690218D02*
Y1691178D01*
G01Y1685898D02*
Y1688778D01*
G01Y1681738D02*
Y1683498D01*
G01Y1677578D02*
Y1679338D01*
G01X77523Y1692938D02*
Y1694698D01*
G01Y1690538D02*
Y1691178D01*
G01Y1685898D02*
Y1688298D01*
G01Y1681738D02*
Y1683498D01*
G01Y1677578D02*
Y1679338D01*
G01X77363Y1692938D02*
Y1694698D01*
G01Y1690858D02*
Y1691178D01*
G01Y1685738D02*
Y1687978D01*
G01Y1681738D02*
Y1683498D01*
G01Y1677578D02*
Y1679338D01*
G01X77203Y1692938D02*
Y1694698D01*
G01Y1685578D02*
Y1687818D01*
G01Y1681738D02*
Y1683498D01*
G01Y1677578D02*
Y1679338D01*
G01X77043Y1692938D02*
Y1694698D01*
G01Y1685578D02*
Y1687658D01*
G01Y1681738D02*
Y1683498D01*
G01Y1677578D02*
Y1679338D01*
G01X76883Y1692938D02*
Y1694698D01*
G01Y1685578D02*
Y1687498D01*
G01Y1681738D02*
Y1683498D01*
G01Y1677578D02*
Y1679338D01*
G01X76723Y1692938D02*
Y1694698D01*
G01Y1685418D02*
Y1687338D01*
G01Y1681738D02*
Y1683498D01*
G01Y1677578D02*
Y1679338D01*
G01X76563Y1692938D02*
Y1694698D01*
G01Y1685418D02*
Y1687338D01*
G01Y1681738D02*
Y1683498D01*
G01Y1677578D02*
Y1679338D01*
G01X76403Y1692938D02*
Y1694698D01*
G01Y1685418D02*
Y1687178D01*
G01Y1681738D02*
Y1683498D01*
G01Y1677578D02*
Y1679338D01*
G01X76243Y1692938D02*
Y1694698D01*
G01Y1685418D02*
Y1687178D01*
G01Y1681738D02*
Y1683498D01*
G01Y1677578D02*
Y1679338D01*
G01X76083Y1692938D02*
Y1694698D01*
G01Y1685258D02*
Y1687178D01*
G01Y1681738D02*
Y1683498D01*
G01Y1677578D02*
Y1679338D01*
G01X75923Y1692938D02*
Y1694698D01*
G01Y1685258D02*
Y1687018D01*
G01Y1681738D02*
Y1683498D01*
G01Y1677578D02*
Y1679338D01*
G01X75763Y1692938D02*
Y1694698D01*
G01Y1685258D02*
Y1687018D01*
G01Y1681738D02*
Y1683498D01*
G01Y1677578D02*
Y1679338D01*
G01X75603Y1692938D02*
Y1694698D01*
G01Y1685258D02*
Y1687018D01*
G01Y1681738D02*
Y1683498D01*
G01Y1677578D02*
Y1679338D01*
G01X75443Y1692938D02*
Y1694698D01*
G01Y1685258D02*
Y1687018D01*
G01Y1681738D02*
Y1683498D01*
G01Y1677578D02*
Y1679338D01*
G01X75283Y1692938D02*
Y1694698D01*
G01Y1685258D02*
Y1687018D01*
G01Y1681738D02*
Y1683498D01*
G01Y1677578D02*
Y1679338D01*
G01X75123Y1692938D02*
Y1694698D01*
G01Y1685258D02*
Y1687018D01*
G01Y1681738D02*
Y1683498D01*
G01Y1677578D02*
Y1679338D01*
G01X74963Y1692938D02*
Y1694698D01*
G01Y1685258D02*
Y1687018D01*
G01Y1681738D02*
Y1683498D01*
G01Y1677578D02*
Y1679338D01*
G01X74803Y1692938D02*
Y1694698D01*
G01Y1685258D02*
Y1687018D01*
G01Y1681738D02*
Y1683498D01*
G01Y1677578D02*
Y1679338D01*
G01X74643Y1692938D02*
Y1694698D01*
G01Y1685258D02*
Y1687018D01*
G01Y1681738D02*
Y1683498D01*
G01Y1677578D02*
Y1679338D01*
G01X74483Y1692938D02*
Y1694858D01*
G01Y1685258D02*
Y1687178D01*
G01Y1681738D02*
Y1683498D01*
G01Y1677578D02*
Y1679338D01*
G01X74323Y1692938D02*
Y1694858D01*
G01Y1685418D02*
Y1687178D01*
G01Y1681738D02*
Y1683498D01*
G01Y1677578D02*
Y1679338D01*
G01X74163Y1692938D02*
Y1694858D01*
G01Y1685418D02*
Y1687178D01*
G01Y1681738D02*
Y1683498D01*
G01Y1677578D02*
Y1679338D01*
G01Y1674538D02*
Y1675978D01*
G01X74003Y1692938D02*
Y1695018D01*
G01Y1685418D02*
Y1687338D01*
G01Y1681738D02*
Y1683498D01*
G01Y1677578D02*
Y1679338D01*
G01Y1674538D02*
Y1676138D01*
G01X73843Y1692938D02*
Y1695018D01*
G01Y1685418D02*
Y1687338D01*
G01Y1681738D02*
Y1683498D01*
G01Y1677578D02*
Y1679338D01*
G01Y1674698D02*
Y1676138D01*
G01X73683Y1692938D02*
Y1695178D01*
G01Y1685578D02*
Y1687498D01*
G01Y1681738D02*
Y1683498D01*
G01Y1677578D02*
Y1679338D01*
G01Y1674698D02*
Y1676298D01*
G01X73523Y1692938D02*
Y1695178D01*
G01Y1685578D02*
Y1687658D01*
G01Y1681738D02*
Y1683498D01*
G01Y1677578D02*
Y1679338D01*
G01Y1674698D02*
Y1676298D01*
G01X77043Y1698538D02*
Y1700618D01*
G01X76883Y1698538D02*
Y1700458D01*
G01X76723Y1698378D02*
Y1700298D01*
G01X76563Y1698378D02*
Y1700298D01*
G01X76403Y1698378D02*
Y1700138D01*
G01X76243Y1698378D02*
Y1700138D01*
G01X76083Y1698218D02*
Y1700138D01*
G01X75923Y1698218D02*
Y1699978D01*
G01X75763Y1698218D02*
Y1699978D01*
G01X75603Y1698218D02*
Y1699978D01*
G01X75443Y1698218D02*
Y1699978D01*
G01X75283Y1698218D02*
Y1699978D01*
G01X75123Y1698218D02*
Y1699978D01*
G01X74963Y1698218D02*
Y1699978D01*
G01X74803Y1698218D02*
Y1699978D01*
G01X74643Y1698218D02*
Y1699978D01*
G01X74483Y1698218D02*
Y1699978D01*
G01X74323Y1698378D02*
Y1700138D01*
G01X74163Y1698378D02*
Y1700138D01*
G01X74003Y1698378D02*
Y1700138D01*
G01X73843Y1698378D02*
Y1700298D01*
G01X73683Y1698538D02*
Y1700298D01*
G01X73523Y1698538D02*
Y1700458D01*
G01X79123Y1716938D02*
Y1718698D01*
G01Y1708618D02*
Y1710378D01*
G01Y1701258D02*
Y1703018D01*
G01X78963Y1716298D02*
Y1719338D01*
G01Y1707978D02*
Y1711178D01*
G01Y1700618D02*
Y1703658D01*
G01X78803Y1715818D02*
Y1719658D01*
G01Y1707498D02*
Y1711498D01*
G01Y1700138D02*
Y1703978D01*
G01X78643Y1715658D02*
Y1719978D01*
G01Y1707338D02*
Y1711818D01*
G01Y1699978D02*
Y1704298D01*
G01X78483Y1715338D02*
Y1720298D01*
G01Y1707338D02*
Y1711978D01*
G01Y1699658D02*
Y1704618D01*
G01X78323Y1715178D02*
Y1720458D01*
G01Y1707338D02*
Y1712138D01*
G01Y1699498D02*
Y1704778D01*
G01X78163Y1715018D02*
Y1720618D01*
G01Y1707338D02*
Y1712298D01*
G01Y1699338D02*
Y1704938D01*
G01X78003Y1714858D02*
Y1720778D01*
G01Y1707338D02*
Y1712458D01*
G01Y1699178D02*
Y1705098D01*
G01X77843Y1714698D02*
Y1720938D01*
G01Y1707338D02*
Y1712458D01*
G01Y1699018D02*
Y1705258D01*
G01X77683Y1718538D02*
Y1721098D01*
G01Y1714538D02*
Y1717258D01*
G01Y1710378D02*
Y1712618D01*
G01Y1707338D02*
Y1708778D01*
G01Y1702858D02*
Y1705418D01*
G01Y1698858D02*
Y1701578D01*
G01X77523Y1718858D02*
Y1721098D01*
G01Y1714538D02*
Y1716778D01*
G01Y1710698D02*
Y1712618D01*
G01Y1707338D02*
Y1708298D01*
G01Y1703178D02*
Y1705418D01*
G01Y1698858D02*
Y1701098D01*
G01X77363Y1719178D02*
Y1721258D01*
G01Y1714378D02*
Y1716618D01*
G01Y1710858D02*
Y1712778D01*
G01Y1707338D02*
Y1707978D01*
G01Y1703498D02*
Y1705578D01*
G01Y1698698D02*
Y1700938D01*
G01X77203Y1719338D02*
Y1721258D01*
G01Y1714378D02*
Y1716298D01*
G01Y1711018D02*
Y1712778D01*
G01Y1707338D02*
Y1707658D01*
G01Y1703658D02*
Y1705578D01*
G01Y1698698D02*
Y1700618D01*
G01X77043Y1719498D02*
Y1721418D01*
G01Y1714218D02*
Y1716298D01*
G01Y1711018D02*
Y1712778D01*
G01Y1703818D02*
Y1705738D01*
G01X76883Y1719658D02*
Y1721418D01*
G01Y1714218D02*
Y1716138D01*
G01Y1711018D02*
Y1712778D01*
G01Y1703978D02*
Y1705738D01*
G01X76723Y1719658D02*
Y1721578D01*
G01Y1714058D02*
Y1715978D01*
G01Y1711018D02*
Y1712778D01*
G01Y1703978D02*
Y1705898D01*
G01X76563Y1719818D02*
Y1721578D01*
G01Y1714058D02*
Y1715978D01*
G01Y1710858D02*
Y1712778D01*
G01Y1704138D02*
Y1705898D01*
G01X76403Y1719818D02*
Y1721578D01*
G01Y1714058D02*
Y1715818D01*
G01Y1710858D02*
Y1712778D01*
G01Y1704138D02*
Y1705898D01*
G01X76243Y1719818D02*
Y1721578D01*
G01Y1714058D02*
Y1715818D01*
G01Y1710538D02*
Y1712618D01*
G01Y1704138D02*
Y1705898D01*
G01X76083Y1719978D02*
Y1721738D01*
G01Y1713898D02*
Y1715818D01*
G01Y1710378D02*
Y1712618D01*
G01Y1704298D02*
Y1706058D01*
G01X75923Y1719978D02*
Y1721738D01*
G01Y1713898D02*
Y1715658D01*
G01Y1709898D02*
Y1712458D01*
G01Y1704298D02*
Y1706058D01*
G01X75763Y1719978D02*
Y1721738D01*
G01Y1713898D02*
Y1715658D01*
G01Y1709418D02*
Y1712458D01*
G01Y1704298D02*
Y1706058D01*
G01X75603Y1719978D02*
Y1721738D01*
G01Y1713898D02*
Y1715658D01*
G01Y1709098D02*
Y1712298D01*
G01Y1704298D02*
Y1706058D01*
G01X75443Y1719978D02*
Y1721738D01*
G01Y1713898D02*
Y1715658D01*
G01Y1708778D02*
Y1712138D01*
G01Y1704298D02*
Y1706058D01*
G01X75283Y1719978D02*
Y1721738D01*
G01Y1713898D02*
Y1715658D01*
G01Y1708458D02*
Y1711978D01*
G01Y1704298D02*
Y1706058D01*
G01X75123Y1719978D02*
Y1721738D01*
G01Y1713898D02*
Y1715658D01*
G01Y1708138D02*
Y1711658D01*
G01Y1704298D02*
Y1706058D01*
G01X74963Y1719978D02*
Y1721738D01*
G01Y1713898D02*
Y1715658D01*
G01Y1707978D02*
Y1711498D01*
G01Y1704298D02*
Y1706058D01*
G01X74803Y1719978D02*
Y1721738D01*
G01Y1713898D02*
Y1715658D01*
G01Y1707818D02*
Y1711178D01*
G01Y1704298D02*
Y1706058D01*
G01X74643Y1719978D02*
Y1721738D01*
G01Y1713898D02*
Y1715658D01*
G01Y1707658D02*
Y1710698D01*
G01Y1704298D02*
Y1706058D01*
G01X74483Y1719978D02*
Y1721738D01*
G01Y1713898D02*
Y1715658D01*
G01Y1707658D02*
Y1710378D01*
G01Y1704298D02*
Y1706058D01*
G01X74323Y1719818D02*
Y1721738D01*
G01Y1714058D02*
Y1715818D01*
G01Y1707498D02*
Y1709898D01*
G01Y1704138D02*
Y1706058D01*
G01X74163Y1719818D02*
Y1721738D01*
G01Y1714058D02*
Y1715818D01*
G01Y1707498D02*
Y1709578D01*
G01Y1704138D02*
Y1706058D01*
G01X74003Y1719818D02*
Y1721578D01*
G01Y1714058D02*
Y1715818D01*
G01Y1707498D02*
Y1709258D01*
G01Y1704138D02*
Y1705898D01*
G01X73843Y1719818D02*
Y1721578D01*
G01Y1714058D02*
Y1715978D01*
G01Y1707338D02*
Y1709258D01*
G01Y1704138D02*
Y1705898D01*
G01X73683Y1719658D02*
Y1721578D01*
G01Y1714218D02*
Y1715978D01*
G01Y1707338D02*
Y1709098D01*
G01Y1703978D02*
Y1705898D01*
G01X73523Y1719658D02*
Y1721578D01*
G01Y1714218D02*
Y1716138D01*
G01Y1707338D02*
Y1709098D01*
G01Y1703978D02*
Y1705898D01*
G01X78963Y1724138D02*
Y1725738D01*
G01X78803Y1724138D02*
Y1725738D01*
G01X78643Y1724138D02*
Y1725738D01*
G01X78483Y1724138D02*
Y1725738D01*
G01X78323Y1724138D02*
Y1725738D01*
G01X78163Y1724138D02*
Y1725738D01*
G01X78003Y1724138D02*
Y1725738D01*
G01X77843Y1724138D02*
Y1725738D01*
G01X77683Y1724138D02*
Y1725738D01*
G01X77523Y1724138D02*
Y1725738D01*
G01X77363Y1724138D02*
Y1725738D01*
G01X77203Y1724138D02*
Y1725738D01*
G01X77043Y1724138D02*
Y1725738D01*
G01X76883Y1724138D02*
Y1725738D01*
G01X76723Y1724138D02*
Y1725738D01*
G01X76563Y1724138D02*
Y1725738D01*
G01X76403Y1724138D02*
Y1725738D01*
G01X76243Y1724138D02*
Y1725738D01*
G01X76083Y1724138D02*
Y1725738D01*
G01X75923Y1724138D02*
Y1725738D01*
G01X75763Y1724138D02*
Y1725738D01*
G01X75603Y1724138D02*
Y1725738D01*
G01X75443Y1724138D02*
Y1725738D01*
G01X75283Y1724138D02*
Y1725738D01*
G01X75123Y1724138D02*
Y1725738D01*
G01X74963Y1724138D02*
Y1725738D01*
G01X74803Y1724138D02*
Y1725738D01*
G01X74643Y1724138D02*
Y1725738D01*
G01X74483Y1724138D02*
Y1725738D01*
G01X74323Y1724138D02*
Y1725738D01*
G01X74163Y1724138D02*
Y1725738D01*
G01X74003Y1724138D02*
Y1725738D01*
G01X73843Y1724138D02*
Y1725738D01*
G01X73683Y1724138D02*
Y1725738D01*
G01X73523Y1724138D02*
Y1725738D01*
G01X79123Y1730698D02*
Y1732298D01*
G01X78963Y1730218D02*
Y1732778D01*
G01X78803Y1730058D02*
Y1732778D01*
G01X78643Y1729898D02*
Y1732778D01*
G01X78483Y1729738D02*
Y1732778D01*
G01X78323Y1729578D02*
Y1732778D01*
G01X78163Y1729578D02*
Y1732778D01*
G01X78003Y1729418D02*
Y1732778D01*
G01X77843Y1729418D02*
Y1732778D01*
G01X77683Y1732458D02*
Y1732778D01*
G01Y1729418D02*
Y1731498D01*
G01X77523Y1729258D02*
Y1731338D01*
G01X77363Y1729258D02*
Y1731178D01*
G01X77203Y1729258D02*
Y1731178D01*
G01X77043Y1729258D02*
Y1731018D01*
G01X76883Y1729258D02*
Y1731018D01*
G01X76723Y1729258D02*
Y1731018D01*
G01X76563Y1729258D02*
Y1731018D01*
G01X76403Y1729258D02*
Y1731018D01*
G01X76243Y1729258D02*
Y1731018D01*
G01X76083Y1729258D02*
Y1731018D01*
G01X75923Y1729258D02*
Y1731018D01*
G01X75763Y1729258D02*
Y1731018D01*
G01X75603Y1729258D02*
Y1731018D01*
G01X75443Y1729258D02*
Y1731018D01*
G01X75283Y1729258D02*
Y1731018D01*
G01X75123Y1729258D02*
Y1731018D01*
G01X74963Y1729258D02*
Y1731018D01*
G01X74803Y1729258D02*
Y1731018D01*
G01X74643Y1729258D02*
Y1731018D01*
G01X74483Y1729258D02*
Y1731018D01*
G01X74323Y1729258D02*
Y1731018D01*
G01X74163Y1729258D02*
Y1731018D01*
G01X74003Y1729258D02*
Y1731018D01*
G01X73843Y1729258D02*
Y1731018D01*
G01X73683Y1729258D02*
Y1731018D01*
G01X73523Y1729258D02*
Y1731018D01*
M02*
